FILE_TYPE = MACRO_DRAWING;
SET COLOR_WIRE YELLOW;
SET COLOR_PROP MONO;
SET COLOR_DOT WHITE;
SET COLOR_ARC YELLOW;
SET COLOR_BODY GREEN;
SET COLOR_NOTE MONO;
SET PROP_DISPLAY VALUE;
SET PAGE_NUMBER P127;
FORCEADD GND..1
(-3425 -2600);
FORCEPROP 3 LASTPIN (-3425 -2550) SIG_NAME GND\g
J 0
(-3415 -2540);
DISPLAY 0.659574 (-3415 -2540);
PAINT MONO (-3415 -2540);
DISPLAY INVISIBLE (-3415 -2540);
FORCEPROP 1 LAST PATH I14
J 0
(-3350 -2600);
DISPLAY 0.872340 (-3350 -2600);
PAINT AQUA (-3350 -2600);
DISPLAY INVISIBLE (-3350 -2600);
FORCEPROP 1 LAST BODY_TYPE PLUMBING
J 0
(-3470 -2643);
DISPLAY 0.340426 (-3470 -2643);
PAINT GREEN (-3470 -2643);
DISPLAY INVISIBLE (-3470 -2643);
FORCEPROP 1 LAST SIZE 1B
J 0
(-3350 -2650);
DISPLAY 1.404255 (-3350 -2650);
PAINT AQUA (-3350 -2650);
DISPLAY INVISIBLE (-3350 -2650);
FORCEPROP 2 LAST CDS_LIB mstr_symbols
J 0
(-3425 -2600);
PAINT ORANGE (-3425 -2600);
DISPLAY INVISIBLE (-3425 -2600);
FORCEPROP 1 LAST HDL_POWER GND
J 0
(-3425 -2450);
PAINT GREEN (-3425 -2450);
DISPLAY INVISIBLE (-3425 -2450);
FORCEPROP 1 LAST VOLTAGE 0.0V
J 0
(-3470 -2643);
DISPLAY 0.340426 (-3470 -2643);
PAINT SKYBLUE (-3470 -2643);
DISPLAY INVISIBLE (-3470 -2643);
FORCEADD P1V05_PCH_STBY..1
(-4275 -1700);
FORCEPROP 3 LASTPIN (-4275 -1750) SIG_NAME P1V05_PCH_STBY\g
J 0
(-4265 -1740);
DISPLAY 0.659574 (-4265 -1740);
PAINT MONO (-4265 -1740);
DISPLAY INVISIBLE (-4265 -1740);
FORCEPROP 1 LAST PATH I16
J 0
(-4225 -1675);
DISPLAY 0.872340 (-4225 -1675);
PAINT AQUA (-4225 -1675);
DISPLAY INVISIBLE (-4225 -1675);
FORCEPROP 1 LAST BODY_TYPE PLUMBING
J 0
(-4320 -1743);
DISPLAY 0.340426 (-4320 -1743);
PAINT GREEN (-4320 -1743);
DISPLAY INVISIBLE (-4320 -1743);
FORCEPROP 2 LAST CDS_LIB mstr_symbols
J 0
(-4275 -1700);
PAINT ORANGE (-4275 -1700);
DISPLAY INVISIBLE (-4275 -1700);
FORCEPROP 1 LAST HDL_POWER P1V05_PCH_STBY
J 0
(-4275 -1650);
DISPLAY 0.872340 (-4275 -1650);
PAINT GREEN (-4275 -1650);
DISPLAY INVISIBLE (-4275 -1650);
FORCEPROP 1 LAST VOLTAGE 1.05V
J 0
(-4320 -1743);
DISPLAY 0.340426 (-4320 -1743);
PAINT SKYBLUE (-4320 -1743);
DISPLAY INVISIBLE (-4320 -1743);
FORCEADD FERRITE..1
(-4025 -2050);
FORCEPROP 1 LASTPIN (-4125 -2050) $PN 1
J 2
(-4090 -2040);
DISPLAY 0.617021 (-4090 -2040);
PAINT WHITE (-4090 -2040);
FORCEPROP 1 LASTPIN (-3925 -2050) $PN 2
J 0
(-3945 -2040);
DISPLAY 0.617021 (-3945 -2040);
PAINT WHITE (-3945 -2040);
FORCEPROP 1 LAST MATERIAL FB
J 0
(-3970 -2150);
DISPLAY 0.617021 (-3970 -2150);
PAINT SKYBLUE (-3970 -2150);
FORCEPROP 1 LAST PACK_TYPE SM
J 0
(-3945 -2100);
DISPLAY 0.617021 (-3945 -2100);
PAINT SKYBLUE (-3945 -2100);
FORCEPROP 1 LAST VALUE 120
J 2
(-4020 -2150);
DISPLAY 0.617021 (-4020 -2150);
PAINT SKYBLUE (-4020 -2150);
FORCEPROP 1 LAST PART_NUMBER 693286-027
J 0
(-4120 -1935);
DISPLAY 0.617021 (-4120 -1935);
PAINT BLUE (-4120 -1935);
FORCEPROP 1 LAST LOCATION FB3M2
J 0
(-4120 -1995);
DISPLAY 0.617021 (-4120 -1995);
PAINT AQUA (-4120 -1995);
FORCEPROP 1 LAST PATH I17
J 0
(-4120 -1885);
DISPLAY 0.872340 (-4120 -1885);
PAINT PURPLE (-4120 -1885);
DISPLAY INVISIBLE (-4120 -1885);
FORCEPROP 2 LAST CDS_LOCATION FB3M2
J 0
(-4120 -1995);
DISPLAY 0.617021 (-4120 -1995);
PAINT AQUA (-4120 -1995);
DISPLAY INVISIBLE (-4120 -1995);
FORCEPROP 2 LAST SEC 1
J 0
(-4100 -1825);
PAINT MONO (-4100 -1825);
DISPLAY INVISIBLE (-4100 -1825);
FORCEPROP 2 LAST SEC_TYPE SM
J 0
(-4100 -1825);
DISPLAY 1.021277 (-4100 -1825);
PAINT ORANGE (-4100 -1825);
DISPLAY INVISIBLE (-4100 -1825);
FORCEPROP 2 LAST CDS_LIB mstr_discrete
J 0
(-4025 -2050);
PAINT ORANGE (-4025 -2050);
DISPLAY INVISIBLE (-4025 -2050);
FORCEPROP 2 LAST BOM_COST SB
J 0
(-4125 -1900);
DISPLAY 1.659574 (-4125 -1900);
PAINT WHITE (-4125 -1900);
DISPLAY INVISIBLE (-4125 -1900);
FORCEPROP 2 LAST ROOM SB_FILTER_PLL1
J 0
(-4125 -1900);
DISPLAY 1.659574 (-4125 -1900);
PAINT WHITE (-4125 -1900);
DISPLAY INVISIBLE (-4125 -1900);
FORCEADD CAP_A..1
R 2
(-4275 -2250);
FORCEPROP 1 LASTPIN (-4275 -2350) $PN 2
J 2
(-4285 -2370);
DISPLAY 0.617021 (-4285 -2370);
PAINT ORANGE (-4285 -2370);
FORCEPROP 1 LASTPIN (-4275 -2150) $PN 1
J 2
(-4285 -2170);
DISPLAY 0.617021 (-4285 -2170);
PAINT ORANGE (-4285 -2170);
FORCEPROP 1 LAST VOLTAGE 6.3V
J 2
(-4325 -2250);
DISPLAY 0.617021 (-4325 -2250);
PAINT SKYBLUE (-4325 -2250);
FORCEPROP 1 LAST PACK_TYPE 0402V
J 2
(-4325 -2450);
DISPLAY 0.617021 (-4325 -2450);
PAINT SKYBLUE (-4325 -2450);
FORCEPROP 1 LAST TOLERANCE 10%
J 2
(-4325 -2300);
DISPLAY 0.617021 (-4325 -2300);
PAINT SKYBLUE (-4325 -2300);
FORCEPROP 1 LAST VALUE 1.0UF
J 2
(-4325 -2200);
DISPLAY 0.617021 (-4325 -2200);
PAINT SKYBLUE (-4325 -2200);
FORCEPROP 1 LAST PART_NUMBER D97712-004
J 2
(-4325 -2400);
DISPLAY 0.617021 (-4325 -2400);
PAINT BLUE (-4325 -2400);
FORCEPROP 1 LAST LOCATION C3M22
J 2
(-4325 -2150);
DISPLAY 0.617021 (-4325 -2150);
PAINT AQUA (-4325 -2150);
FORCEPROP 1 LAST MATERIAL X6S
J 2
(-4325 -2350);
DISPLAY 0.617021 (-4325 -2350);
PAINT SKYBLUE (-4325 -2350);
FORCEPROP 1 LAST PATH I18
J 2
(-4325 -2100);
DISPLAY 0.978723 (-4325 -2100);
PAINT WHITE (-4325 -2100);
DISPLAY INVISIBLE (-4325 -2100);
FORCEPROP 2 LAST SEC 1
J 0
(-4325 -2050);
PAINT MONO (-4325 -2050);
DISPLAY INVISIBLE (-4325 -2050);
FORCEPROP 2 LAST SEC_TYPE 0402V
J 0
(-4325 -2050);
DISPLAY 1.021277 (-4325 -2050);
PAINT ORANGE (-4325 -2050);
DISPLAY INVISIBLE (-4325 -2050);
FORCEPROP 2 LAST CDS_SEC 1
J 0
(-4325 -2100);
PAINT ORANGE (-4325 -2100);
DISPLAY INVISIBLE (-4325 -2100);
FORCEPROP 2 LAST CDS_LIB dev_discrete
J 0
(-4275 -2250);
PAINT ORANGE (-4275 -2250);
DISPLAY INVISIBLE (-4275 -2250);
FORCEPROP 2 LAST BOM_COST SB
J 2
(-4325 -2100);
DISPLAY 1.659574 (-4325 -2100);
PAINT WHITE (-4325 -2100);
DISPLAY INVISIBLE (-4325 -2100);
FORCEPROP 2 LAST CDS_LOCATION C3M22
J 2
(-4325 -2150);
DISPLAY 0.617021 (-4325 -2150);
PAINT AQUA (-4325 -2150);
DISPLAY INVISIBLE (-4325 -2150);
FORCEPROP 2 LAST ROOM SB_FILTER_PLL1
J 2
(-4325 -2100);
DISPLAY 1.659574 (-4325 -2100);
PAINT WHITE (-4325 -2100);
DISPLAY INVISIBLE (-4325 -2100);
FORCEADD GND..1
(-3400 -3900);
FORCEPROP 3 LASTPIN (-3400 -3850) SIG_NAME GND\g
J 0
(-3390 -3840);
DISPLAY 0.659574 (-3390 -3840);
PAINT MONO (-3390 -3840);
DISPLAY INVISIBLE (-3390 -3840);
FORCEPROP 1 LAST PATH I23
J 0
(-3325 -3900);
DISPLAY 0.872340 (-3325 -3900);
PAINT AQUA (-3325 -3900);
DISPLAY INVISIBLE (-3325 -3900);
FORCEPROP 1 LAST BODY_TYPE PLUMBING
J 0
(-3445 -3943);
DISPLAY 0.340426 (-3445 -3943);
PAINT GREEN (-3445 -3943);
DISPLAY INVISIBLE (-3445 -3943);
FORCEPROP 1 LAST SIZE 1B
J 0
(-3325 -3950);
DISPLAY 1.404255 (-3325 -3950);
PAINT AQUA (-3325 -3950);
DISPLAY INVISIBLE (-3325 -3950);
FORCEPROP 2 LAST CDS_LIB mstr_symbols
J 0
(-3400 -3900);
PAINT ORANGE (-3400 -3900);
DISPLAY INVISIBLE (-3400 -3900);
FORCEPROP 1 LAST HDL_POWER GND
J 0
(-3400 -3750);
PAINT GREEN (-3400 -3750);
DISPLAY INVISIBLE (-3400 -3750);
FORCEPROP 1 LAST VOLTAGE 0.0V
J 0
(-3445 -3943);
DISPLAY 0.340426 (-3445 -3943);
PAINT SKYBLUE (-3445 -3943);
DISPLAY INVISIBLE (-3445 -3943);
FORCEADD P1V05_PCH_STBY..1
(-4250 -3000);
FORCEPROP 3 LASTPIN (-4250 -3050) SIG_NAME P1V05_PCH_STBY\g
J 0
(-4240 -3040);
DISPLAY 0.659574 (-4240 -3040);
PAINT MONO (-4240 -3040);
DISPLAY INVISIBLE (-4240 -3040);
FORCEPROP 1 LAST PATH I25
J 0
(-4200 -2975);
DISPLAY 0.872340 (-4200 -2975);
PAINT AQUA (-4200 -2975);
DISPLAY INVISIBLE (-4200 -2975);
FORCEPROP 1 LAST BODY_TYPE PLUMBING
J 0
(-4295 -3043);
DISPLAY 0.340426 (-4295 -3043);
PAINT GREEN (-4295 -3043);
DISPLAY INVISIBLE (-4295 -3043);
FORCEPROP 2 LAST CDS_LIB mstr_symbols
J 0
(-4250 -3000);
PAINT ORANGE (-4250 -3000);
DISPLAY INVISIBLE (-4250 -3000);
FORCEPROP 1 LAST HDL_POWER P1V05_PCH_STBY
J 0
(-4250 -2950);
DISPLAY 0.872340 (-4250 -2950);
PAINT GREEN (-4250 -2950);
DISPLAY INVISIBLE (-4250 -2950);
FORCEPROP 1 LAST VOLTAGE 1.05V
J 0
(-4295 -3043);
DISPLAY 0.340426 (-4295 -3043);
PAINT SKYBLUE (-4295 -3043);
DISPLAY INVISIBLE (-4295 -3043);
FORCEADD FERRITE..1
(-4000 -3350);
FORCEPROP 1 LASTPIN (-4100 -3350) $PN 1
J 2
(-4065 -3340);
DISPLAY 0.617021 (-4065 -3340);
PAINT WHITE (-4065 -3340);
FORCEPROP 1 LASTPIN (-3900 -3350) $PN 2
J 0
(-3920 -3340);
DISPLAY 0.617021 (-3920 -3340);
PAINT WHITE (-3920 -3340);
FORCEPROP 1 LAST MATERIAL FB
J 0
(-3945 -3450);
DISPLAY 0.617021 (-3945 -3450);
PAINT SKYBLUE (-3945 -3450);
FORCEPROP 1 LAST PACK_TYPE SM
J 0
(-3920 -3400);
DISPLAY 0.617021 (-3920 -3400);
PAINT SKYBLUE (-3920 -3400);
FORCEPROP 1 LAST VALUE 120
J 2
(-3995 -3450);
DISPLAY 0.617021 (-3995 -3450);
PAINT SKYBLUE (-3995 -3450);
FORCEPROP 1 LAST PART_NUMBER 693286-027
J 0
(-4095 -3235);
DISPLAY 0.617021 (-4095 -3235);
PAINT BLUE (-4095 -3235);
FORCEPROP 1 LAST LOCATION FB3M3
J 0
(-4095 -3295);
DISPLAY 0.617021 (-4095 -3295);
PAINT AQUA (-4095 -3295);
FORCEPROP 1 LAST PATH I26
J 0
(-4095 -3185);
DISPLAY 0.872340 (-4095 -3185);
PAINT PURPLE (-4095 -3185);
DISPLAY INVISIBLE (-4095 -3185);
FORCEPROP 2 LAST CDS_LOCATION FB3M3
J 0
(-4095 -3295);
DISPLAY 0.617021 (-4095 -3295);
PAINT AQUA (-4095 -3295);
DISPLAY INVISIBLE (-4095 -3295);
FORCEPROP 2 LAST SEC 1
J 0
(-4075 -3125);
PAINT MONO (-4075 -3125);
DISPLAY INVISIBLE (-4075 -3125);
FORCEPROP 2 LAST SEC_TYPE SM
J 0
(-4075 -3125);
DISPLAY 1.021277 (-4075 -3125);
PAINT ORANGE (-4075 -3125);
DISPLAY INVISIBLE (-4075 -3125);
FORCEPROP 2 LAST BOM_COST SB
J 0
(-4100 -3200);
DISPLAY 1.659574 (-4100 -3200);
PAINT WHITE (-4100 -3200);
DISPLAY INVISIBLE (-4100 -3200);
FORCEPROP 2 LAST CDS_LIB mstr_discrete
J 0
(-4000 -3350);
PAINT ORANGE (-4000 -3350);
DISPLAY INVISIBLE (-4000 -3350);
FORCEPROP 2 LAST ROOM SB_FILTER_XTAL
J 0
(-4100 -3200);
DISPLAY 1.659574 (-4100 -3200);
PAINT WHITE (-4100 -3200);
DISPLAY INVISIBLE (-4100 -3200);
FORCEADD CAP_A..1
R 2
(-4250 -3550);
FORCEPROP 1 LASTPIN (-4250 -3650) $PN 2
J 2
(-4260 -3670);
DISPLAY 0.617021 (-4260 -3670);
PAINT ORANGE (-4260 -3670);
FORCEPROP 1 LASTPIN (-4250 -3450) $PN 1
J 2
(-4260 -3470);
DISPLAY 0.617021 (-4260 -3470);
PAINT ORANGE (-4260 -3470);
FORCEPROP 1 LAST MATERIAL X6S
J 2
(-4300 -3650);
DISPLAY 0.617021 (-4300 -3650);
PAINT SKYBLUE (-4300 -3650);
FORCEPROP 1 LAST VOLTAGE 6.3V
J 2
(-4300 -3550);
DISPLAY 0.617021 (-4300 -3550);
PAINT SKYBLUE (-4300 -3550);
FORCEPROP 1 LAST PACK_TYPE 0402V
J 2
(-4300 -3750);
DISPLAY 0.617021 (-4300 -3750);
PAINT SKYBLUE (-4300 -3750);
FORCEPROP 1 LAST TOLERANCE 10%
J 2
(-4300 -3600);
DISPLAY 0.617021 (-4300 -3600);
PAINT SKYBLUE (-4300 -3600);
FORCEPROP 1 LAST VALUE 1.0UF
J 2
(-4300 -3500);
DISPLAY 0.617021 (-4300 -3500);
PAINT SKYBLUE (-4300 -3500);
FORCEPROP 1 LAST PART_NUMBER D97712-004
J 2
(-4300 -3700);
DISPLAY 0.617021 (-4300 -3700);
PAINT BLUE (-4300 -3700);
FORCEPROP 1 LAST LOCATION C3M30
J 2
(-4300 -3450);
DISPLAY 0.617021 (-4300 -3450);
PAINT AQUA (-4300 -3450);
FORCEPROP 1 LAST PATH I27
J 2
(-4300 -3400);
DISPLAY 0.978723 (-4300 -3400);
PAINT WHITE (-4300 -3400);
DISPLAY INVISIBLE (-4300 -3400);
FORCEPROP 2 LAST SEC 1
J 0
(-4300 -3350);
PAINT MONO (-4300 -3350);
DISPLAY INVISIBLE (-4300 -3350);
FORCEPROP 2 LAST SEC_TYPE 0402V
J 0
(-4300 -3350);
DISPLAY 1.021277 (-4300 -3350);
PAINT ORANGE (-4300 -3350);
DISPLAY INVISIBLE (-4300 -3350);
FORCEPROP 2 LAST CDS_SEC 1
J 0
(-4300 -3400);
PAINT ORANGE (-4300 -3400);
DISPLAY INVISIBLE (-4300 -3400);
FORCEPROP 2 LAST CDS_LIB dev_discrete
J 0
(-4250 -3550);
PAINT ORANGE (-4250 -3550);
DISPLAY INVISIBLE (-4250 -3550);
FORCEPROP 2 LAST BOM_COST SB
J 2
(-4300 -3400);
DISPLAY 1.659574 (-4300 -3400);
PAINT WHITE (-4300 -3400);
DISPLAY INVISIBLE (-4300 -3400);
FORCEPROP 2 LAST CDS_LOCATION C3M30
J 2
(-4300 -3450);
DISPLAY 0.617021 (-4300 -3450);
PAINT AQUA (-4300 -3450);
DISPLAY INVISIBLE (-4300 -3450);
FORCEPROP 2 LAST ROOM SB_FILTER_XTAL
J 2
(-4300 -3400);
DISPLAY 1.659574 (-4300 -3400);
PAINT WHITE (-4300 -3400);
DISPLAY INVISIBLE (-4300 -3400);
FORCEADD GND..1
(-2575 -1325);
FORCEPROP 3 LASTPIN (-2575 -1275) SIG_NAME GND\g
J 0
(-2565 -1265);
DISPLAY 0.659574 (-2565 -1265);
PAINT MONO (-2565 -1265);
DISPLAY INVISIBLE (-2565 -1265);
FORCEPROP 1 LAST PATH I32
J 0
(-2500 -1325);
DISPLAY 0.872340 (-2500 -1325);
PAINT AQUA (-2500 -1325);
DISPLAY INVISIBLE (-2500 -1325);
FORCEPROP 1 LAST BODY_TYPE PLUMBING
J 0
(-2620 -1368);
DISPLAY 0.340426 (-2620 -1368);
PAINT GREEN (-2620 -1368);
DISPLAY INVISIBLE (-2620 -1368);
FORCEPROP 1 LAST SIZE 1B
J 0
(-2500 -1375);
DISPLAY 1.404255 (-2500 -1375);
PAINT AQUA (-2500 -1375);
DISPLAY INVISIBLE (-2500 -1375);
FORCEPROP 2 LAST CDS_LIB mstr_symbols
J 0
(-2575 -1325);
PAINT ORANGE (-2575 -1325);
DISPLAY INVISIBLE (-2575 -1325);
FORCEPROP 1 LAST HDL_POWER GND
J 0
(-2575 -1175);
PAINT GREEN (-2575 -1175);
DISPLAY INVISIBLE (-2575 -1175);
FORCEPROP 1 LAST VOLTAGE 0.0V
J 0
(-2620 -1368);
DISPLAY 0.340426 (-2620 -1368);
PAINT SKYBLUE (-2620 -1368);
DISPLAY INVISIBLE (-2620 -1368);
FORCEADD GND..1
(-2575 -2600);
FORCEPROP 3 LASTPIN (-2575 -2550) SIG_NAME GND\g
J 0
(-2565 -2540);
DISPLAY 0.659574 (-2565 -2540);
PAINT MONO (-2565 -2540);
DISPLAY INVISIBLE (-2565 -2540);
FORCEPROP 1 LAST PATH I34
J 0
(-2500 -2600);
DISPLAY 0.872340 (-2500 -2600);
PAINT AQUA (-2500 -2600);
DISPLAY INVISIBLE (-2500 -2600);
FORCEPROP 1 LAST BODY_TYPE PLUMBING
J 0
(-2620 -2643);
DISPLAY 0.340426 (-2620 -2643);
PAINT GREEN (-2620 -2643);
DISPLAY INVISIBLE (-2620 -2643);
FORCEPROP 2 LAST CDS_LIB mstr_symbols
J 0
(-2575 -2600);
PAINT ORANGE (-2575 -2600);
DISPLAY INVISIBLE (-2575 -2600);
FORCEPROP 1 LAST SIZE 1B
J 0
(-2500 -2650);
DISPLAY 1.404255 (-2500 -2650);
PAINT AQUA (-2500 -2650);
DISPLAY INVISIBLE (-2500 -2650);
FORCEPROP 1 LAST HDL_POWER GND
J 0
(-2575 -2450);
PAINT GREEN (-2575 -2450);
DISPLAY INVISIBLE (-2575 -2450);
FORCEPROP 1 LAST VOLTAGE 0.0V
J 0
(-2620 -2643);
DISPLAY 0.340426 (-2620 -2643);
PAINT SKYBLUE (-2620 -2643);
DISPLAY INVISIBLE (-2620 -2643);
FORCEADD GND..1
(-2550 -3850);
FORCEPROP 3 LASTPIN (-2550 -3800) SIG_NAME GND\g
J 0
(-2540 -3790);
DISPLAY 0.659574 (-2540 -3790);
PAINT MONO (-2540 -3790);
DISPLAY INVISIBLE (-2540 -3790);
FORCEPROP 1 LAST PATH I36
J 0
(-2475 -3850);
DISPLAY 0.872340 (-2475 -3850);
PAINT AQUA (-2475 -3850);
DISPLAY INVISIBLE (-2475 -3850);
FORCEPROP 1 LAST BODY_TYPE PLUMBING
J 0
(-2595 -3893);
DISPLAY 0.340426 (-2595 -3893);
PAINT GREEN (-2595 -3893);
DISPLAY INVISIBLE (-2595 -3893);
FORCEPROP 1 LAST SIZE 1B
J 0
(-2475 -3900);
DISPLAY 1.404255 (-2475 -3900);
PAINT AQUA (-2475 -3900);
DISPLAY INVISIBLE (-2475 -3900);
FORCEPROP 2 LAST CDS_LIB mstr_symbols
J 0
(-2550 -3850);
PAINT ORANGE (-2550 -3850);
DISPLAY INVISIBLE (-2550 -3850);
FORCEPROP 1 LAST HDL_POWER GND
J 0
(-2550 -3700);
PAINT GREEN (-2550 -3700);
DISPLAY INVISIBLE (-2550 -3700);
FORCEPROP 1 LAST VOLTAGE 0.0V
J 0
(-2595 -3893);
DISPLAY 0.340426 (-2595 -3893);
PAINT SKYBLUE (-2595 -3893);
DISPLAY INVISIBLE (-2595 -3893);
FORCEADD P1V05_PCH_STBY_VCCA_XTAL..1
(-2550 -2975);
FORCEPROP 3 LASTPIN (-2550 -3025) SIG_NAME P1V05_PCH_STBY_VCCA_XTAL\g
J 0
(-2540 -3015);
DISPLAY 0.659574 (-2540 -3015);
PAINT MONO (-2540 -3015);
DISPLAY INVISIBLE (-2540 -3015);
FORCEPROP 1 LAST PATH I39
J 0
(-2500 -2950);
DISPLAY 0.872340 (-2500 -2950);
PAINT AQUA (-2500 -2950);
DISPLAY INVISIBLE (-2500 -2950);
FORCEPROP 1 LAST BODY_TYPE PLUMBING
J 0
(-2595 -3018);
DISPLAY 0.340426 (-2595 -3018);
PAINT GREEN (-2595 -3018);
DISPLAY INVISIBLE (-2595 -3018);
FORCEPROP 2 LAST CDS_LIB mstr_symbols
J 0
(-2550 -2975);
PAINT ORANGE (-2550 -2975);
DISPLAY INVISIBLE (-2550 -2975);
FORCEPROP 2 LAST BOM_COST SB
J 0
(-2550 -2825);
PAINT MONO (-2550 -2825);
DISPLAY INVISIBLE (-2550 -2825);
FORCEPROP 2 LAST ROOM SB_DECOUPLING
J 0
(-2550 -2875);
DISPLAY 1.361702 (-2550 -2875);
PAINT WHITE (-2550 -2875);
DISPLAY INVISIBLE (-2550 -2875);
FORCEPROP 1 LAST HDL_POWER P1V05_PCH_STBY_VCCA_XTAL
J 1
(-2550 -2925);
DISPLAY 0.872340 (-2550 -2925);
PAINT GREEN (-2550 -2925);
DISPLAY INVISIBLE (-2550 -2925);
FORCEPROP 1 LAST VOLTAGE 1.05V
J 0
(-2595 -3018);
DISPLAY 0.340426 (-2595 -3018);
PAINT SKYBLUE (-2595 -3018);
DISPLAY INVISIBLE (-2595 -3018);
FORCEADD P1V05_PCH_STBY_WM20_PLL..1
(1850 -750);
FORCEPROP 3 LASTPIN (1850 -800) SIG_NAME P1V05_PCH_STBY_WM20_PLL\g
J 0
(1860 -790);
DISPLAY 0.659574 (1860 -790);
PAINT MONO (1860 -790);
DISPLAY INVISIBLE (1860 -790);
FORCEPROP 2 LAST BOM_COST SB
J 0
(1850 -600);
PAINT MONO (1850 -600);
DISPLAY INVISIBLE (1850 -600);
FORCEPROP 2 LAST CDS_LIB mstr_symbols
J 0
(1850 -750);
PAINT ORANGE (1850 -750);
DISPLAY INVISIBLE (1850 -750);
FORCEPROP 1 LAST BODY_TYPE PLUMBING
J 0
(1805 -793);
DISPLAY 0.340426 (1805 -793);
PAINT GREEN (1805 -793);
DISPLAY INVISIBLE (1805 -793);
FORCEPROP 1 LAST PATH I40
J 0
(1900 -725);
DISPLAY 0.872340 (1900 -725);
PAINT AQUA (1900 -725);
DISPLAY INVISIBLE (1900 -725);
FORCEPROP 2 LAST ROOM SB_DECOUPLING
J 0
(1850 -650);
DISPLAY 1.361702 (1850 -650);
PAINT WHITE (1850 -650);
DISPLAY INVISIBLE (1850 -650);
FORCEPROP 1 LAST HDL_POWER P1V05_PCH_STBY_WM20_PLL
J 1
(1850 -700);
DISPLAY 0.872340 (1850 -700);
PAINT GREEN (1850 -700);
DISPLAY INVISIBLE (1850 -700);
FORCEPROP 1 LAST VOLTAGE 1.05V
J 0
(1805 -793);
DISPLAY 0.340426 (1805 -793);
PAINT SKYBLUE (1805 -793);
DISPLAY INVISIBLE (1805 -793);
FORCEADD CAP..1
(1850 -1375);
FORCEPROP 1 LASTPIN (1850 -1275) $PN 1
J 0
(1860 -1295);
DISPLAY 0.617021 (1860 -1295);
PAINT ORANGE (1860 -1295);
FORCEPROP 1 LASTPIN (1850 -1475) $PN 2
J 0
(1860 -1495);
DISPLAY 0.617021 (1860 -1495);
PAINT ORANGE (1860 -1495);
FORCEPROP 1 LAST MATERIAL X6S
J 0
(1900 -1475);
DISPLAY 0.617021 (1900 -1475);
PAINT SKYBLUE (1900 -1475);
FORCEPROP 1 LAST VOLTAGE 4V
J 0
(1900 -1375);
DISPLAY 0.617021 (1900 -1375);
PAINT SKYBLUE (1900 -1375);
FORCEPROP 1 LAST PACK_TYPE 0603LF
J 0
(1900 -1575);
DISPLAY 0.617021 (1900 -1575);
PAINT SKYBLUE (1900 -1575);
FORCEPROP 1 LAST TOLERANCE 20%
J 0
(1900 -1425);
DISPLAY 0.617021 (1900 -1425);
PAINT SKYBLUE (1900 -1425);
FORCEPROP 1 LAST VALUE 10UF
J 0
(1900 -1325);
DISPLAY 0.617021 (1900 -1325);
PAINT SKYBLUE (1900 -1325);
FORCEPROP 1 LAST PART_NUMBER E15431-001
J 0
(1900 -1525);
DISPLAY 0.617021 (1900 -1525);
PAINT BLUE (1900 -1525);
FORCEPROP 1 LAST LOCATION C2M5
J 0
(1900 -1275);
DISPLAY 0.617021 (1900 -1275);
PAINT AQUA (1900 -1275);
FORCEPROP 1 LAST PATH I43
J 0
(1900 -1225);
DISPLAY 0.978723 (1900 -1225);
PAINT WHITE (1900 -1225);
DISPLAY INVISIBLE (1900 -1225);
FORCEPROP 2 LAST CDS_LOCATION C2M5
J 0
(1900 -1275);
DISPLAY 0.617021 (1900 -1275);
PAINT AQUA (1900 -1275);
DISPLAY INVISIBLE (1900 -1275);
FORCEPROP 2 LAST SEC 1
J 0
(1900 -1175);
DISPLAY 0.680851 (1900 -1175);
PAINT MONO (1900 -1175);
DISPLAY INVISIBLE (1900 -1175);
FORCEPROP 2 LAST SEC_TYPE 0603LF
J 0
(1900 -1175);
DISPLAY 1.021277 (1900 -1175);
PAINT ORANGE (1900 -1175);
DISPLAY INVISIBLE (1900 -1175);
FORCEPROP 2 LAST BOM_COST SB
J 0
(1900 -1225);
DISPLAY 1.659574 (1900 -1225);
PAINT WHITE (1900 -1225);
DISPLAY INVISIBLE (1900 -1225);
FORCEPROP 2 LAST CDS_LIB mstr_discrete
J 0
(1850 -1375);
PAINT ORANGE (1850 -1375);
DISPLAY INVISIBLE (1850 -1375);
FORCEPROP 2 LAST ROOM SB_FILTER_VM20
J 0
(1900 -1225);
DISPLAY 1.659574 (1900 -1225);
PAINT WHITE (1900 -1225);
DISPLAY INVISIBLE (1900 -1225);
FORCEADD CAP_A..1
(1400 -1375);
FORCEPROP 1 LASTPIN (1400 -1475) $PN 2
J 0
(1410 -1495);
DISPLAY 0.617021 (1410 -1495);
PAINT ORANGE (1410 -1495);
FORCEPROP 1 LASTPIN (1400 -1275) $PN 1
J 0
(1410 -1295);
DISPLAY 0.617021 (1410 -1295);
PAINT ORANGE (1410 -1295);
FORCEPROP 1 LAST MATERIAL X6S
J 0
(1450 -1475);
DISPLAY 0.617021 (1450 -1475);
PAINT SKYBLUE (1450 -1475);
FORCEPROP 1 LAST VOLTAGE 6.3V
J 0
(1450 -1375);
DISPLAY 0.617021 (1450 -1375);
PAINT SKYBLUE (1450 -1375);
FORCEPROP 1 LAST PACK_TYPE 0402V
J 0
(1450 -1575);
DISPLAY 0.617021 (1450 -1575);
PAINT SKYBLUE (1450 -1575);
FORCEPROP 1 LAST TOLERANCE 10%
J 0
(1450 -1425);
DISPLAY 0.617021 (1450 -1425);
PAINT SKYBLUE (1450 -1425);
FORCEPROP 1 LAST VALUE 1.0UF
J 0
(1450 -1325);
DISPLAY 0.617021 (1450 -1325);
PAINT SKYBLUE (1450 -1325);
FORCEPROP 1 LAST PART_NUMBER D97712-004
J 0
(1450 -1525);
DISPLAY 0.617021 (1450 -1525);
PAINT BLUE (1450 -1525);
FORCEPROP 1 LAST LOCATION C2M7
J 0
(1450 -1275);
DISPLAY 0.617021 (1450 -1275);
PAINT AQUA (1450 -1275);
FORCEPROP 1 LAST PATH I44
J 0
(1450 -1225);
DISPLAY 0.978723 (1450 -1225);
PAINT WHITE (1450 -1225);
DISPLAY INVISIBLE (1450 -1225);
FORCEPROP 2 LAST SEC 1
J 0
(1450 -1175);
DISPLAY 0.680851 (1450 -1175);
PAINT MONO (1450 -1175);
DISPLAY INVISIBLE (1450 -1175);
FORCEPROP 2 LAST SEC_TYPE 0402V
J 0
(1450 -1175);
DISPLAY 1.021277 (1450 -1175);
PAINT ORANGE (1450 -1175);
DISPLAY INVISIBLE (1450 -1175);
FORCEPROP 2 LAST CDS_SEC 1
J 0
(1450 -1225);
PAINT ORANGE (1450 -1225);
DISPLAY INVISIBLE (1450 -1225);
FORCEPROP 2 LAST CDS_LIB dev_discrete
J 0
(1400 -1375);
PAINT ORANGE (1400 -1375);
DISPLAY INVISIBLE (1400 -1375);
FORCEPROP 2 LAST BOM_COST SB
J 0
(1450 -1225);
DISPLAY 1.659574 (1450 -1225);
PAINT WHITE (1450 -1225);
DISPLAY INVISIBLE (1450 -1225);
FORCEPROP 2 LAST CDS_LOCATION C2M7
J 0
(1450 -1275);
DISPLAY 0.617021 (1450 -1275);
PAINT AQUA (1450 -1275);
DISPLAY INVISIBLE (1450 -1275);
FORCEPROP 2 LAST ROOM SB_FILTER_VM20
J 0
(1450 -1225);
DISPLAY 1.659574 (1450 -1225);
PAINT WHITE (1450 -1225);
DISPLAY INVISIBLE (1450 -1225);
FORCEADD P1V05_PCH_STBY..1
(950 -825);
FORCEPROP 3 LASTPIN (950 -875) SIG_NAME P1V05_PCH_STBY\g
J 0
(960 -865);
DISPLAY 0.659574 (960 -865);
PAINT MONO (960 -865);
DISPLAY INVISIBLE (960 -865);
FORCEPROP 1 LAST PATH I45
J 0
(1000 -800);
DISPLAY 0.872340 (1000 -800);
PAINT AQUA (1000 -800);
DISPLAY INVISIBLE (1000 -800);
FORCEPROP 1 LAST BODY_TYPE PLUMBING
J 0
(905 -868);
DISPLAY 0.340426 (905 -868);
PAINT GREEN (905 -868);
DISPLAY INVISIBLE (905 -868);
FORCEPROP 2 LAST CDS_LIB mstr_symbols
J 0
(950 -825);
PAINT ORANGE (950 -825);
DISPLAY INVISIBLE (950 -825);
FORCEPROP 1 LAST HDL_POWER P1V05_PCH_STBY
J 0
(950 -775);
DISPLAY 0.872340 (950 -775);
PAINT GREEN (950 -775);
DISPLAY INVISIBLE (950 -775);
FORCEPROP 1 LAST VOLTAGE 1.05V
J 0
(905 -868);
DISPLAY 0.340426 (905 -868);
PAINT SKYBLUE (905 -868);
DISPLAY INVISIBLE (905 -868);
FORCEADD FERRITE..1
(1150 -1175);
FORCEPROP 1 LASTPIN (1050 -1175) $PN 1
J 2
(1085 -1165);
DISPLAY 0.617021 (1085 -1165);
PAINT WHITE (1085 -1165);
FORCEPROP 1 LASTPIN (1250 -1175) $PN 2
J 0
(1230 -1165);
DISPLAY 0.617021 (1230 -1165);
PAINT WHITE (1230 -1165);
FORCEPROP 1 LAST MATERIAL FB
J 0
(1205 -1275);
DISPLAY 0.617021 (1205 -1275);
PAINT SKYBLUE (1205 -1275);
FORCEPROP 1 LAST PACK_TYPE SM
J 0
(1230 -1225);
DISPLAY 0.617021 (1230 -1225);
PAINT SKYBLUE (1230 -1225);
FORCEPROP 1 LAST VALUE 120
J 2
(1155 -1275);
DISPLAY 0.617021 (1155 -1275);
PAINT SKYBLUE (1155 -1275);
FORCEPROP 1 LAST LOCATION FB2M1
J 0
(1055 -1120);
DISPLAY 0.617021 (1055 -1120);
PAINT AQUA (1055 -1120);
FORCEPROP 1 LAST PART_NUMBER 693286-027
J 0
(1055 -1060);
DISPLAY 0.617021 (1055 -1060);
PAINT BLUE (1055 -1060);
FORCEPROP 1 LAST PATH I46
J 0
(1055 -1010);
DISPLAY 0.872340 (1055 -1010);
PAINT PURPLE (1055 -1010);
DISPLAY INVISIBLE (1055 -1010);
FORCEPROP 2 LAST CDS_LOCATION FB2M1
J 0
(1055 -1120);
DISPLAY 0.617021 (1055 -1120);
PAINT AQUA (1055 -1120);
DISPLAY INVISIBLE (1055 -1120);
FORCEPROP 2 LAST SEC 1
J 0
(1075 -950);
DISPLAY 0.680851 (1075 -950);
PAINT MONO (1075 -950);
DISPLAY INVISIBLE (1075 -950);
FORCEPROP 2 LAST CDS_LIB mstr_discrete
J 0
(1150 -1175);
PAINT ORANGE (1150 -1175);
DISPLAY INVISIBLE (1150 -1175);
FORCEPROP 2 LAST SEC_TYPE SM
J 0
(1075 -950);
DISPLAY 1.021277 (1075 -950);
PAINT ORANGE (1075 -950);
DISPLAY INVISIBLE (1075 -950);
FORCEPROP 2 LAST BOM_COST SB
J 0
(1050 -1025);
DISPLAY 1.659574 (1050 -1025);
PAINT WHITE (1050 -1025);
DISPLAY INVISIBLE (1050 -1025);
FORCEPROP 2 LAST ROOM SB_FILTER_VM20
J 0
(1050 -1025);
DISPLAY 1.659574 (1050 -1025);
PAINT WHITE (1050 -1025);
DISPLAY INVISIBLE (1050 -1025);
FORCEADD P1V05_PCH_STBY_WM26_PLL..1
(-500 -800);
FORCEPROP 3 LASTPIN (-500 -850) SIG_NAME P1V05_PCH_STBY_WM26_PLL\g
J 0
(-490 -840);
DISPLAY 0.659574 (-490 -840);
PAINT MONO (-490 -840);
DISPLAY INVISIBLE (-490 -840);
FORCEPROP 1 LAST PATH I47
J 0
(-450 -775);
DISPLAY 0.872340 (-450 -775);
PAINT AQUA (-450 -775);
DISPLAY INVISIBLE (-450 -775);
FORCEPROP 1 LAST BODY_TYPE PLUMBING
J 0
(-545 -843);
DISPLAY 0.340426 (-545 -843);
PAINT GREEN (-545 -843);
DISPLAY INVISIBLE (-545 -843);
FORCEPROP 2 LAST CDS_LIB mstr_symbols
J 0
(-500 -800);
PAINT ORANGE (-500 -800);
DISPLAY INVISIBLE (-500 -800);
FORCEPROP 2 LAST BOM_COST SB
J 0
(-500 -650);
PAINT MONO (-500 -650);
DISPLAY INVISIBLE (-500 -650);
FORCEPROP 2 LAST ROOM SB_DECOUPLING
J 0
(-500 -700);
DISPLAY 1.361702 (-500 -700);
PAINT WHITE (-500 -700);
DISPLAY INVISIBLE (-500 -700);
FORCEPROP 1 LAST HDL_POWER P1V05_PCH_STBY_WM26_PLL
J 1
(-500 -750);
DISPLAY 0.872340 (-500 -750);
PAINT GREEN (-500 -750);
DISPLAY INVISIBLE (-500 -750);
FORCEPROP 1 LAST VOLTAGE 1.05V
J 0
(-545 -843);
DISPLAY 0.340426 (-545 -843);
PAINT SKYBLUE (-545 -843);
DISPLAY INVISIBLE (-545 -843);
FORCEADD CAP..1
(-500 -1400);
FORCEPROP 1 LASTPIN (-500 -1300) $PN 1
J 0
(-490 -1320);
DISPLAY 0.617021 (-490 -1320);
PAINT ORANGE (-490 -1320);
FORCEPROP 1 LAST MATERIAL X6S
J 0
(-450 -1500);
DISPLAY 0.617021 (-450 -1500);
PAINT SKYBLUE (-450 -1500);
FORCEPROP 1 LAST VOLTAGE 4V
J 0
(-450 -1400);
DISPLAY 0.617021 (-450 -1400);
PAINT SKYBLUE (-450 -1400);
FORCEPROP 1 LAST VALUE 10UF
J 0
(-450 -1350);
DISPLAY 0.617021 (-450 -1350);
PAINT SKYBLUE (-450 -1350);
FORCEPROP 1 LAST LOCATION C2M10
J 0
(-450 -1300);
DISPLAY 0.617021 (-450 -1300);
PAINT AQUA (-450 -1300);
FORCEPROP 1 LAST TOLERANCE 20%
J 0
(-450 -1450);
DISPLAY 0.617021 (-450 -1450);
PAINT SKYBLUE (-450 -1450);
FORCEPROP 1 LAST PACK_TYPE 0603LF
J 0
(-450 -1600);
DISPLAY 0.617021 (-450 -1600);
PAINT SKYBLUE (-450 -1600);
FORCEPROP 1 LAST PART_NUMBER E15431-001
J 0
(-450 -1550);
DISPLAY 0.617021 (-450 -1550);
PAINT BLUE (-450 -1550);
FORCEPROP 1 LASTPIN (-500 -1500) $PN 2
J 0
(-490 -1520);
DISPLAY 0.617021 (-490 -1520);
PAINT ORANGE (-490 -1520);
FORCEPROP 1 LAST PATH I49
J 0
(-450 -1250);
DISPLAY 0.978723 (-450 -1250);
PAINT WHITE (-450 -1250);
DISPLAY INVISIBLE (-450 -1250);
FORCEPROP 2 LAST CDS_LOCATION C2M10
J 0
(-450 -1300);
DISPLAY 0.617021 (-450 -1300);
PAINT AQUA (-450 -1300);
DISPLAY INVISIBLE (-450 -1300);
FORCEPROP 2 LAST SEC 1
J 0
(-450 -1200);
DISPLAY 0.680851 (-450 -1200);
PAINT MONO (-450 -1200);
DISPLAY INVISIBLE (-450 -1200);
FORCEPROP 2 LAST CDS_LIB mstr_discrete
J 0
(-500 -1400);
PAINT ORANGE (-500 -1400);
DISPLAY INVISIBLE (-500 -1400);
FORCEPROP 2 LAST BOM_COST SB
J 0
(-450 -1250);
DISPLAY 1.659574 (-450 -1250);
PAINT WHITE (-450 -1250);
DISPLAY INVISIBLE (-450 -1250);
FORCEPROP 2 LAST SEC_TYPE 0603LF
J 0
(-450 -1200);
DISPLAY 1.021277 (-450 -1200);
PAINT ORANGE (-450 -1200);
DISPLAY INVISIBLE (-450 -1200);
FORCEPROP 2 LAST ROOM SB_FILTER_VM26
J 0
(-450 -1250);
DISPLAY 1.659574 (-450 -1250);
PAINT WHITE (-450 -1250);
DISPLAY INVISIBLE (-450 -1250);
FORCEADD CAP_A..1
(-1000 -1400);
FORCEPROP 1 LASTPIN (-1000 -1500) $PN 2
J 0
(-990 -1520);
DISPLAY 0.617021 (-990 -1520);
PAINT ORANGE (-990 -1520);
FORCEPROP 1 LASTPIN (-1000 -1300) $PN 1
J 0
(-990 -1320);
DISPLAY 0.617021 (-990 -1320);
PAINT ORANGE (-990 -1320);
FORCEPROP 1 LAST MATERIAL X6S
J 0
(-950 -1500);
DISPLAY 0.617021 (-950 -1500);
PAINT SKYBLUE (-950 -1500);
FORCEPROP 1 LAST VOLTAGE 6.3V
J 0
(-950 -1400);
DISPLAY 0.617021 (-950 -1400);
PAINT SKYBLUE (-950 -1400);
FORCEPROP 1 LAST PACK_TYPE 0402V
J 0
(-950 -1600);
DISPLAY 0.617021 (-950 -1600);
PAINT SKYBLUE (-950 -1600);
FORCEPROP 1 LAST TOLERANCE 10%
J 0
(-950 -1450);
DISPLAY 0.617021 (-950 -1450);
PAINT SKYBLUE (-950 -1450);
FORCEPROP 1 LAST VALUE 1.0UF
J 0
(-950 -1350);
DISPLAY 0.617021 (-950 -1350);
PAINT SKYBLUE (-950 -1350);
FORCEPROP 1 LAST PART_NUMBER D97712-004
J 0
(-950 -1550);
DISPLAY 0.617021 (-950 -1550);
PAINT BLUE (-950 -1550);
FORCEPROP 1 LAST LOCATION C2M9
J 0
(-950 -1300);
DISPLAY 0.617021 (-950 -1300);
PAINT AQUA (-950 -1300);
FORCEPROP 1 LAST PATH I50
J 0
(-950 -1250);
DISPLAY 0.978723 (-950 -1250);
PAINT WHITE (-950 -1250);
DISPLAY INVISIBLE (-950 -1250);
FORCEPROP 2 LAST SEC 1
J 0
(-950 -1200);
DISPLAY 0.680851 (-950 -1200);
PAINT MONO (-950 -1200);
DISPLAY INVISIBLE (-950 -1200);
FORCEPROP 2 LAST SEC_TYPE 0402V
J 0
(-950 -1200);
DISPLAY 1.021277 (-950 -1200);
PAINT ORANGE (-950 -1200);
DISPLAY INVISIBLE (-950 -1200);
FORCEPROP 2 LAST CDS_SEC 1
J 0
(-950 -1250);
PAINT ORANGE (-950 -1250);
DISPLAY INVISIBLE (-950 -1250);
FORCEPROP 2 LAST CDS_LIB dev_discrete
J 0
(-1000 -1400);
PAINT ORANGE (-1000 -1400);
DISPLAY INVISIBLE (-1000 -1400);
FORCEPROP 2 LAST BOM_COST SB
J 0
(-950 -1250);
DISPLAY 1.659574 (-950 -1250);
PAINT WHITE (-950 -1250);
DISPLAY INVISIBLE (-950 -1250);
FORCEPROP 2 LAST CDS_LOCATION C2M9
J 0
(-950 -1300);
DISPLAY 0.617021 (-950 -1300);
PAINT AQUA (-950 -1300);
DISPLAY INVISIBLE (-950 -1300);
FORCEPROP 2 LAST ROOM SB_FILTER_VM26
J 0
(-950 -1250);
DISPLAY 1.659574 (-950 -1250);
PAINT WHITE (-950 -1250);
DISPLAY INVISIBLE (-950 -1250);
FORCEADD GND..1
(1400 -1725);
FORCEPROP 3 LASTPIN (1400 -1675) SIG_NAME GND\g
J 0
(1410 -1665);
DISPLAY 0.659574 (1410 -1665);
PAINT MONO (1410 -1665);
DISPLAY INVISIBLE (1410 -1665);
FORCEPROP 1 LAST PATH I51
J 0
(1475 -1725);
DISPLAY 0.872340 (1475 -1725);
PAINT AQUA (1475 -1725);
DISPLAY INVISIBLE (1475 -1725);
FORCEPROP 1 LAST BODY_TYPE PLUMBING
J 0
(1355 -1768);
DISPLAY 0.340426 (1355 -1768);
PAINT GREEN (1355 -1768);
DISPLAY INVISIBLE (1355 -1768);
FORCEPROP 1 LAST SIZE 1B
J 0
(1475 -1775);
DISPLAY 1.404255 (1475 -1775);
PAINT AQUA (1475 -1775);
DISPLAY INVISIBLE (1475 -1775);
FORCEPROP 2 LAST CDS_LIB mstr_symbols
J 0
(1400 -1725);
PAINT MONO (1400 -1725);
DISPLAY INVISIBLE (1400 -1725);
FORCEPROP 1 LAST HDL_POWER GND
J 0
(1400 -1575);
PAINT GREEN (1400 -1575);
DISPLAY INVISIBLE (1400 -1575);
FORCEPROP 1 LAST VOLTAGE 0.0V
J 0
(1355 -1768);
DISPLAY 0.340426 (1355 -1768);
PAINT SKYBLUE (1355 -1768);
DISPLAY INVISIBLE (1355 -1768);
FORCEADD P1V05_PCH_STBY_ISCLK_PLL..1
(1700 -2700);
FORCEPROP 3 LASTPIN (1700 -2750) SIG_NAME P1V05_PCH_STBY_ISCLK_PLL\g
J 0
(1710 -2740);
DISPLAY 0.659574 (1710 -2740);
PAINT MONO (1710 -2740);
DISPLAY INVISIBLE (1710 -2740);
FORCEPROP 1 LAST PATH I52
J 0
(1750 -2675);
DISPLAY 0.872340 (1750 -2675);
PAINT AQUA (1750 -2675);
DISPLAY INVISIBLE (1750 -2675);
FORCEPROP 1 LAST BODY_TYPE PLUMBING
J 0
(1655 -2743);
DISPLAY 0.340426 (1655 -2743);
PAINT GREEN (1655 -2743);
DISPLAY INVISIBLE (1655 -2743);
FORCEPROP 2 LAST CDS_LIB mstr_symbols
J 0
(1700 -2700);
PAINT ORANGE (1700 -2700);
DISPLAY INVISIBLE (1700 -2700);
FORCEPROP 2 LAST BOM_COST SB
J 0
(1700 -2550);
PAINT MONO (1700 -2550);
DISPLAY INVISIBLE (1700 -2550);
FORCEPROP 2 LAST ROOM SB_DECOUPLING
J 0
(1700 -2600);
DISPLAY 1.361702 (1700 -2600);
PAINT WHITE (1700 -2600);
DISPLAY INVISIBLE (1700 -2600);
FORCEPROP 1 LAST HDL_POWER P1V05_PCH_STBY_ISCLK_PLL
J 1
(1700 -2650);
DISPLAY 0.872340 (1700 -2650);
PAINT GREEN (1700 -2650);
DISPLAY INVISIBLE (1700 -2650);
FORCEPROP 1 LAST VOLTAGE 1.05V
J 0
(1655 -2743);
DISPLAY 0.340426 (1655 -2743);
PAINT SKYBLUE (1655 -2743);
DISPLAY INVISIBLE (1655 -2743);
FORCEADD P1V05_PCH_STBY..1
(950 -2725);
FORCEPROP 3 LASTPIN (950 -2775) SIG_NAME P1V05_PCH_STBY\g
J 0
(960 -2765);
DISPLAY 0.659574 (960 -2765);
PAINT MONO (960 -2765);
DISPLAY INVISIBLE (960 -2765);
FORCEPROP 1 LAST PATH I55
J 0
(1000 -2700);
DISPLAY 0.872340 (1000 -2700);
PAINT AQUA (1000 -2700);
DISPLAY INVISIBLE (1000 -2700);
FORCEPROP 1 LAST BODY_TYPE PLUMBING
J 0
(905 -2768);
DISPLAY 0.340426 (905 -2768);
PAINT GREEN (905 -2768);
DISPLAY INVISIBLE (905 -2768);
FORCEPROP 2 LAST CDS_LIB mstr_symbols
J 0
(950 -2725);
PAINT ORANGE (950 -2725);
DISPLAY INVISIBLE (950 -2725);
FORCEPROP 1 LAST HDL_POWER P1V05_PCH_STBY
J 0
(950 -2675);
DISPLAY 0.872340 (950 -2675);
PAINT GREEN (950 -2675);
DISPLAY INVISIBLE (950 -2675);
FORCEPROP 1 LAST VOLTAGE 1.05V
J 0
(905 -2768);
DISPLAY 0.340426 (905 -2768);
PAINT SKYBLUE (905 -2768);
DISPLAY INVISIBLE (905 -2768);
FORCEADD FERRITE..1
(1150 -3075);
FORCEPROP 1 LASTPIN (1050 -3075) $PN 1
J 2
(1085 -3065);
DISPLAY 0.617021 (1085 -3065);
PAINT WHITE (1085 -3065);
FORCEPROP 1 LASTPIN (1250 -3075) $PN 2
J 0
(1230 -3065);
DISPLAY 0.617021 (1230 -3065);
PAINT WHITE (1230 -3065);
FORCEPROP 1 LAST MATERIAL FB
J 0
(1205 -3175);
DISPLAY 0.617021 (1205 -3175);
PAINT SKYBLUE (1205 -3175);
FORCEPROP 1 LAST PACK_TYPE SM
J 0
(1230 -3125);
DISPLAY 0.617021 (1230 -3125);
PAINT SKYBLUE (1230 -3125);
FORCEPROP 1 LAST VALUE 120
J 2
(1155 -3175);
DISPLAY 0.617021 (1155 -3175);
PAINT SKYBLUE (1155 -3175);
FORCEPROP 1 LAST PART_NUMBER 693286-027
J 0
(1055 -2960);
DISPLAY 0.617021 (1055 -2960);
PAINT BLUE (1055 -2960);
FORCEPROP 1 LAST LOCATION FB3M4
J 0
(1055 -3020);
DISPLAY 0.617021 (1055 -3020);
PAINT AQUA (1055 -3020);
FORCEPROP 1 LAST PATH I56
J 0
(1055 -2910);
DISPLAY 0.872340 (1055 -2910);
PAINT PURPLE (1055 -2910);
DISPLAY INVISIBLE (1055 -2910);
FORCEPROP 2 LAST CDS_LOCATION FB3M4
J 0
(1055 -3020);
DISPLAY 0.617021 (1055 -3020);
PAINT AQUA (1055 -3020);
DISPLAY INVISIBLE (1055 -3020);
FORCEPROP 2 LAST SEC 1
J 0
(1075 -2850);
DISPLAY 0.680851 (1075 -2850);
PAINT MONO (1075 -2850);
DISPLAY INVISIBLE (1075 -2850);
FORCEPROP 2 LAST CDS_LIB mstr_discrete
J 0
(1150 -3075);
PAINT ORANGE (1150 -3075);
DISPLAY INVISIBLE (1150 -3075);
FORCEPROP 2 LAST SEC_TYPE SM
J 0
(1075 -2850);
DISPLAY 1.021277 (1075 -2850);
PAINT ORANGE (1075 -2850);
DISPLAY INVISIBLE (1075 -2850);
FORCEPROP 2 LAST BOM_COST SB
J 0
(1050 -2925);
DISPLAY 1.659574 (1050 -2925);
PAINT WHITE (1050 -2925);
DISPLAY INVISIBLE (1050 -2925);
FORCEPROP 2 LAST ROOM SB_FILTER_ISCLK
J 0
(1050 -2925);
DISPLAY 1.659574 (1050 -2925);
PAINT WHITE (1050 -2925);
DISPLAY INVISIBLE (1050 -2925);
FORCEADD CAP_A..1
R 2
(950 -3275);
FORCEPROP 1 LASTPIN (950 -3375) $PN 2
J 2
(940 -3395);
DISPLAY 0.617021 (940 -3395);
PAINT ORANGE (940 -3395);
FORCEPROP 1 LASTPIN (950 -3175) $PN 1
J 2
(940 -3195);
DISPLAY 0.617021 (940 -3195);
PAINT ORANGE (940 -3195);
FORCEPROP 1 LAST MATERIAL X6S
J 2
(900 -3375);
DISPLAY 0.617021 (900 -3375);
PAINT SKYBLUE (900 -3375);
FORCEPROP 1 LAST VOLTAGE 6.3V
J 2
(900 -3275);
DISPLAY 0.617021 (900 -3275);
PAINT SKYBLUE (900 -3275);
FORCEPROP 1 LAST PACK_TYPE 0402V
J 2
(900 -3475);
DISPLAY 0.617021 (900 -3475);
PAINT SKYBLUE (900 -3475);
FORCEPROP 1 LAST TOLERANCE 10%
J 2
(900 -3325);
DISPLAY 0.617021 (900 -3325);
PAINT SKYBLUE (900 -3325);
FORCEPROP 1 LAST VALUE 1.0UF
J 2
(900 -3225);
DISPLAY 0.617021 (900 -3225);
PAINT SKYBLUE (900 -3225);
FORCEPROP 1 LAST PART_NUMBER D97712-004
J 2
(900 -3425);
DISPLAY 0.617021 (900 -3425);
PAINT BLUE (900 -3425);
FORCEPROP 1 LAST LOCATION C3M31
J 2
(900 -3175);
DISPLAY 0.617021 (900 -3175);
PAINT AQUA (900 -3175);
FORCEPROP 1 LAST PATH I57
J 2
(900 -3125);
DISPLAY 0.978723 (900 -3125);
PAINT WHITE (900 -3125);
DISPLAY INVISIBLE (900 -3125);
FORCEPROP 2 LAST SEC 1
J 0
(900 -3075);
DISPLAY 0.680851 (900 -3075);
PAINT MONO (900 -3075);
DISPLAY INVISIBLE (900 -3075);
FORCEPROP 2 LAST SEC_TYPE 0402V
J 0
(900 -3075);
DISPLAY 1.021277 (900 -3075);
PAINT ORANGE (900 -3075);
DISPLAY INVISIBLE (900 -3075);
FORCEPROP 2 LAST CDS_SEC 1
J 0
(900 -3125);
PAINT ORANGE (900 -3125);
DISPLAY INVISIBLE (900 -3125);
FORCEPROP 2 LAST CDS_LIB dev_discrete
J 0
(950 -3275);
PAINT ORANGE (950 -3275);
DISPLAY INVISIBLE (950 -3275);
FORCEPROP 2 LAST BOM_COST SB
J 2
(900 -3125);
DISPLAY 1.659574 (900 -3125);
PAINT WHITE (900 -3125);
DISPLAY INVISIBLE (900 -3125);
FORCEPROP 2 LAST CDS_LOCATION C3M31
J 2
(900 -3175);
DISPLAY 0.617021 (900 -3175);
PAINT AQUA (900 -3175);
DISPLAY INVISIBLE (900 -3175);
FORCEPROP 2 LAST ROOM SB_FILTER_ISCLK
J 2
(900 -3125);
DISPLAY 1.659574 (900 -3125);
PAINT WHITE (900 -3125);
DISPLAY INVISIBLE (900 -3125);
FORCEADD GND..1
(1700 -3625);
FORCEPROP 3 LASTPIN (1700 -3575) SIG_NAME GND\g
J 0
(1710 -3565);
DISPLAY 0.659574 (1710 -3565);
PAINT MONO (1710 -3565);
DISPLAY INVISIBLE (1710 -3565);
FORCEPROP 1 LAST PATH I58
J 0
(1775 -3625);
DISPLAY 0.872340 (1775 -3625);
PAINT AQUA (1775 -3625);
DISPLAY INVISIBLE (1775 -3625);
FORCEPROP 1 LAST BODY_TYPE PLUMBING
J 0
(1655 -3668);
DISPLAY 0.340426 (1655 -3668);
PAINT GREEN (1655 -3668);
DISPLAY INVISIBLE (1655 -3668);
FORCEPROP 2 LAST CDS_LIB mstr_symbols
J 0
(1700 -3625);
PAINT ORANGE (1700 -3625);
DISPLAY INVISIBLE (1700 -3625);
FORCEPROP 1 LAST SIZE 1B
J 0
(1775 -3675);
DISPLAY 1.404255 (1775 -3675);
PAINT AQUA (1775 -3675);
DISPLAY INVISIBLE (1775 -3675);
FORCEPROP 1 LAST HDL_POWER GND
J 0
(1700 -3475);
PAINT GREEN (1700 -3475);
DISPLAY INVISIBLE (1700 -3475);
FORCEPROP 1 LAST VOLTAGE 0.0V
J 0
(1655 -3668);
DISPLAY 0.340426 (1655 -3668);
PAINT SKYBLUE (1655 -3668);
DISPLAY INVISIBLE (1655 -3668);
FORCEADD GND..1
(950 -3675);
FORCEPROP 3 LASTPIN (950 -3625) SIG_NAME GND\g
J 0
(960 -3615);
DISPLAY 0.659574 (960 -3615);
PAINT MONO (960 -3615);
DISPLAY INVISIBLE (960 -3615);
FORCEPROP 1 LAST PATH I59
J 0
(1025 -3675);
DISPLAY 0.872340 (1025 -3675);
PAINT AQUA (1025 -3675);
DISPLAY INVISIBLE (1025 -3675);
FORCEPROP 1 LAST BODY_TYPE PLUMBING
J 0
(905 -3718);
DISPLAY 0.340426 (905 -3718);
PAINT GREEN (905 -3718);
DISPLAY INVISIBLE (905 -3718);
FORCEPROP 1 LAST SIZE 1B
J 0
(1025 -3725);
DISPLAY 1.404255 (1025 -3725);
PAINT AQUA (1025 -3725);
DISPLAY INVISIBLE (1025 -3725);
FORCEPROP 2 LAST CDS_LIB mstr_symbols
J 0
(950 -3675);
PAINT MONO (950 -3675);
DISPLAY INVISIBLE (950 -3675);
FORCEPROP 1 LAST HDL_POWER GND
J 0
(950 -3525);
PAINT GREEN (950 -3525);
DISPLAY INVISIBLE (950 -3525);
FORCEPROP 1 LAST VOLTAGE 0.0V
J 0
(905 -3718);
DISPLAY 0.340426 (905 -3718);
PAINT SKYBLUE (905 -3718);
DISPLAY INVISIBLE (905 -3718);
FORCEADD GND..1
(-3450 -1400);
FORCEPROP 3 LASTPIN (-3450 -1350) SIG_NAME GND\g
J 0
(-3440 -1340);
DISPLAY 0.659574 (-3440 -1340);
PAINT MONO (-3440 -1340);
DISPLAY INVISIBLE (-3440 -1340);
FORCEPROP 1 LAST PATH I6
J 0
(-3375 -1400);
DISPLAY 0.872340 (-3375 -1400);
PAINT AQUA (-3375 -1400);
DISPLAY INVISIBLE (-3375 -1400);
FORCEPROP 1 LAST BODY_TYPE PLUMBING
J 0
(-3495 -1443);
DISPLAY 0.340426 (-3495 -1443);
PAINT GREEN (-3495 -1443);
DISPLAY INVISIBLE (-3495 -1443);
FORCEPROP 2 LAST CDS_LIB mstr_symbols
J 0
(-3450 -1400);
PAINT ORANGE (-3450 -1400);
DISPLAY INVISIBLE (-3450 -1400);
FORCEPROP 1 LAST SIZE 1B
J 0
(-3375 -1450);
DISPLAY 1.404255 (-3375 -1450);
PAINT AQUA (-3375 -1450);
DISPLAY INVISIBLE (-3375 -1450);
FORCEPROP 1 LAST HDL_POWER GND
J 0
(-3450 -1250);
PAINT GREEN (-3450 -1250);
DISPLAY INVISIBLE (-3450 -1250);
FORCEPROP 1 LAST VOLTAGE 0.0V
J 0
(-3495 -1443);
DISPLAY 0.340426 (-3495 -1443);
PAINT SKYBLUE (-3495 -1443);
DISPLAY INVISIBLE (-3495 -1443);
FORCEADD GND..1
(-1000 -1750);
FORCEPROP 3 LASTPIN (-1000 -1700) SIG_NAME GND\g
J 0
(-990 -1690);
DISPLAY 0.659574 (-990 -1690);
PAINT MONO (-990 -1690);
DISPLAY INVISIBLE (-990 -1690);
FORCEPROP 1 LAST PATH I61
J 0
(-925 -1750);
DISPLAY 0.872340 (-925 -1750);
PAINT AQUA (-925 -1750);
DISPLAY INVISIBLE (-925 -1750);
FORCEPROP 1 LAST BODY_TYPE PLUMBING
J 0
(-1045 -1793);
DISPLAY 0.340426 (-1045 -1793);
PAINT GREEN (-1045 -1793);
DISPLAY INVISIBLE (-1045 -1793);
FORCEPROP 2 LAST CDS_LIB mstr_symbols
J 0
(-1000 -1750);
PAINT MONO (-1000 -1750);
DISPLAY INVISIBLE (-1000 -1750);
FORCEPROP 1 LAST SIZE 1B
J 0
(-925 -1800);
DISPLAY 1.404255 (-925 -1800);
PAINT AQUA (-925 -1800);
DISPLAY INVISIBLE (-925 -1800);
FORCEPROP 1 LAST HDL_POWER GND
J 0
(-1000 -1600);
PAINT GREEN (-1000 -1600);
DISPLAY INVISIBLE (-1000 -1600);
FORCEPROP 1 LAST VOLTAGE 0.0V
J 0
(-1045 -1793);
DISPLAY 0.340426 (-1045 -1793);
PAINT SKYBLUE (-1045 -1793);
DISPLAY INVISIBLE (-1045 -1793);
FORCEADD P1V05_PCH_STBY_KR_PLL..1
(-500 -2650);
FORCEPROP 3 LASTPIN (-500 -2700) SIG_NAME P1V05_PCH_STBY_KR_PLL\g
J 0
(-490 -2690);
DISPLAY 0.659574 (-490 -2690);
PAINT MONO (-490 -2690);
DISPLAY INVISIBLE (-490 -2690);
FORCEPROP 2 LAST BOM_COST SB
J 0
(-500 -2500);
PAINT MONO (-500 -2500);
DISPLAY INVISIBLE (-500 -2500);
FORCEPROP 2 LAST CDS_LIB mstr_symbols
J 0
(-500 -2650);
PAINT ORANGE (-500 -2650);
DISPLAY INVISIBLE (-500 -2650);
FORCEPROP 1 LAST BODY_TYPE PLUMBING
J 0
(-545 -2693);
DISPLAY 0.340426 (-545 -2693);
PAINT GREEN (-545 -2693);
DISPLAY INVISIBLE (-545 -2693);
FORCEPROP 1 LAST PATH I62
J 0
(-450 -2625);
DISPLAY 0.872340 (-450 -2625);
PAINT AQUA (-450 -2625);
DISPLAY INVISIBLE (-450 -2625);
FORCEPROP 2 LAST ROOM SB_DECOUPLING
J 0
(-500 -2550);
DISPLAY 1.361702 (-500 -2550);
PAINT WHITE (-500 -2550);
DISPLAY INVISIBLE (-500 -2550);
FORCEPROP 1 LAST HDL_POWER P1V05_PCH_STBY_KR_PLL
J 1
(-500 -2600);
DISPLAY 0.872340 (-500 -2600);
PAINT GREEN (-500 -2600);
DISPLAY INVISIBLE (-500 -2600);
FORCEPROP 1 LAST VOLTAGE 1.05V
J 0
(-545 -2693);
DISPLAY 0.340426 (-545 -2693);
PAINT SKYBLUE (-545 -2693);
DISPLAY INVISIBLE (-545 -2693);
FORCEADD CAP..1
(-500 -3300);
FORCEPROP 1 LASTPIN (-500 -3200) $PN 1
J 0
(-490 -3220);
DISPLAY 0.617021 (-490 -3220);
PAINT ORANGE (-490 -3220);
FORCEPROP 1 LASTPIN (-500 -3400) $PN 2
J 0
(-490 -3420);
DISPLAY 0.617021 (-490 -3420);
PAINT ORANGE (-490 -3420);
FORCEPROP 1 LAST MATERIAL X6S
J 0
(-450 -3400);
DISPLAY 0.617021 (-450 -3400);
PAINT SKYBLUE (-450 -3400);
FORCEPROP 1 LAST VOLTAGE 4V
J 0
(-450 -3300);
DISPLAY 0.617021 (-450 -3300);
PAINT SKYBLUE (-450 -3300);
FORCEPROP 1 LAST TOLERANCE 20%
J 0
(-450 -3350);
DISPLAY 0.617021 (-450 -3350);
PAINT SKYBLUE (-450 -3350);
FORCEPROP 1 LAST VALUE 10UF
J 0
(-450 -3250);
DISPLAY 0.617021 (-450 -3250);
PAINT SKYBLUE (-450 -3250);
FORCEPROP 1 LAST PART_NUMBER E15431-001
J 0
(-450 -3450);
DISPLAY 0.617021 (-450 -3450);
PAINT BLUE (-450 -3450);
FORCEPROP 1 LAST LOCATION C2N6
J 0
(-450 -3200);
DISPLAY 0.617021 (-450 -3200);
PAINT AQUA (-450 -3200);
FORCEPROP 1 LAST PACK_TYPE 0603LF
J 0
(-450 -3500);
DISPLAY 0.617021 (-450 -3500);
PAINT SKYBLUE (-450 -3500);
FORCEPROP 1 LAST PATH I64
J 0
(-450 -3150);
DISPLAY 0.978723 (-450 -3150);
PAINT WHITE (-450 -3150);
DISPLAY INVISIBLE (-450 -3150);
FORCEPROP 2 LAST CDS_LOCATION C2N6
J 0
(-450 -3200);
DISPLAY 0.617021 (-450 -3200);
PAINT AQUA (-450 -3200);
DISPLAY INVISIBLE (-450 -3200);
FORCEPROP 2 LAST SEC 1
J 0
(-450 -3100);
DISPLAY 0.680851 (-450 -3100);
PAINT MONO (-450 -3100);
DISPLAY INVISIBLE (-450 -3100);
FORCEPROP 2 LAST CDS_LIB mstr_discrete
J 0
(-500 -3300);
PAINT ORANGE (-500 -3300);
DISPLAY INVISIBLE (-500 -3300);
FORCEPROP 2 LAST BOM_COST SB
J 0
(-450 -3150);
DISPLAY 1.659574 (-450 -3150);
PAINT WHITE (-450 -3150);
DISPLAY INVISIBLE (-450 -3150);
FORCEPROP 2 LAST SEC_TYPE 0603LF
J 0
(-450 -3100);
DISPLAY 1.021277 (-450 -3100);
PAINT ORANGE (-450 -3100);
DISPLAY INVISIBLE (-450 -3100);
FORCEPROP 2 LAST ROOM SB_FILTER_KR_PLL
J 0
(-450 -3150);
DISPLAY 1.659574 (-450 -3150);
PAINT WHITE (-450 -3150);
DISPLAY INVISIBLE (-450 -3150);
FORCEADD CAP_A..1
(-1000 -3300);
FORCEPROP 1 LASTPIN (-1000 -3400) $PN 2
J 0
(-990 -3420);
DISPLAY 0.617021 (-990 -3420);
PAINT ORANGE (-990 -3420);
FORCEPROP 1 LASTPIN (-1000 -3200) $PN 1
J 0
(-990 -3220);
DISPLAY 0.617021 (-990 -3220);
PAINT ORANGE (-990 -3220);
FORCEPROP 1 LAST MATERIAL X6S
J 0
(-950 -3400);
DISPLAY 0.617021 (-950 -3400);
PAINT SKYBLUE (-950 -3400);
FORCEPROP 1 LAST VOLTAGE 6.3V
J 0
(-950 -3300);
DISPLAY 0.617021 (-950 -3300);
PAINT SKYBLUE (-950 -3300);
FORCEPROP 1 LAST PACK_TYPE 0402V
J 0
(-950 -3500);
DISPLAY 0.617021 (-950 -3500);
PAINT SKYBLUE (-950 -3500);
FORCEPROP 1 LAST TOLERANCE 10%
J 0
(-950 -3350);
DISPLAY 0.617021 (-950 -3350);
PAINT SKYBLUE (-950 -3350);
FORCEPROP 1 LAST VALUE 1.0UF
J 0
(-950 -3250);
DISPLAY 0.617021 (-950 -3250);
PAINT SKYBLUE (-950 -3250);
FORCEPROP 1 LAST PART_NUMBER D97712-004
J 0
(-950 -3450);
DISPLAY 0.617021 (-950 -3450);
PAINT BLUE (-950 -3450);
FORCEPROP 1 LAST LOCATION C2N5
J 0
(-950 -3200);
DISPLAY 0.617021 (-950 -3200);
PAINT AQUA (-950 -3200);
FORCEPROP 1 LAST PATH I65
J 0
(-950 -3150);
DISPLAY 0.978723 (-950 -3150);
PAINT WHITE (-950 -3150);
DISPLAY INVISIBLE (-950 -3150);
FORCEPROP 2 LAST SEC 1
J 0
(-950 -3100);
DISPLAY 0.680851 (-950 -3100);
PAINT MONO (-950 -3100);
DISPLAY INVISIBLE (-950 -3100);
FORCEPROP 2 LAST SEC_TYPE 0402V
J 0
(-950 -3100);
DISPLAY 1.021277 (-950 -3100);
PAINT ORANGE (-950 -3100);
DISPLAY INVISIBLE (-950 -3100);
FORCEPROP 2 LAST CDS_SEC 1
J 0
(-950 -3150);
PAINT ORANGE (-950 -3150);
DISPLAY INVISIBLE (-950 -3150);
FORCEPROP 2 LAST CDS_LIB dev_discrete
J 0
(-1000 -3300);
PAINT ORANGE (-1000 -3300);
DISPLAY INVISIBLE (-1000 -3300);
FORCEPROP 2 LAST BOM_COST SB
J 0
(-950 -3150);
DISPLAY 1.659574 (-950 -3150);
PAINT WHITE (-950 -3150);
DISPLAY INVISIBLE (-950 -3150);
FORCEPROP 2 LAST CDS_LOCATION C2N5
J 0
(-950 -3200);
DISPLAY 0.617021 (-950 -3200);
PAINT AQUA (-950 -3200);
DISPLAY INVISIBLE (-950 -3200);
FORCEPROP 2 LAST ROOM SB_FILTER_KR_PLL
J 0
(-950 -3150);
DISPLAY 1.659574 (-950 -3150);
PAINT WHITE (-950 -3150);
DISPLAY INVISIBLE (-950 -3150);
FORCEADD GND..1
(-500 -3650);
FORCEPROP 3 LASTPIN (-500 -3600) SIG_NAME GND\g
J 0
(-490 -3590);
DISPLAY 0.659574 (-490 -3590);
PAINT MONO (-490 -3590);
DISPLAY INVISIBLE (-490 -3590);
FORCEPROP 1 LAST PATH I66
J 0
(-425 -3650);
DISPLAY 0.872340 (-425 -3650);
PAINT AQUA (-425 -3650);
DISPLAY INVISIBLE (-425 -3650);
FORCEPROP 1 LAST BODY_TYPE PLUMBING
J 0
(-545 -3693);
DISPLAY 0.340426 (-545 -3693);
PAINT GREEN (-545 -3693);
DISPLAY INVISIBLE (-545 -3693);
FORCEPROP 1 LAST SIZE 1B
J 0
(-425 -3700);
DISPLAY 1.404255 (-425 -3700);
PAINT AQUA (-425 -3700);
DISPLAY INVISIBLE (-425 -3700);
FORCEPROP 2 LAST CDS_LIB mstr_symbols
J 0
(-500 -3650);
PAINT MONO (-500 -3650);
DISPLAY INVISIBLE (-500 -3650);
FORCEPROP 1 LAST HDL_POWER GND
J 0
(-500 -3500);
PAINT GREEN (-500 -3500);
DISPLAY INVISIBLE (-500 -3500);
FORCEPROP 1 LAST VOLTAGE 0.0V
J 0
(-545 -3693);
DISPLAY 0.340426 (-545 -3693);
PAINT SKYBLUE (-545 -3693);
DISPLAY INVISIBLE (-545 -3693);
FORCEADD P1V05_PCH_STBY..1
(-1450 -850);
FORCEPROP 3 LASTPIN (-1450 -900) SIG_NAME P1V05_PCH_STBY\g
J 0
(-1440 -890);
DISPLAY 0.659574 (-1440 -890);
PAINT MONO (-1440 -890);
DISPLAY INVISIBLE (-1440 -890);
FORCEPROP 1 LAST PATH I68
J 0
(-1400 -825);
DISPLAY 0.872340 (-1400 -825);
PAINT AQUA (-1400 -825);
DISPLAY INVISIBLE (-1400 -825);
FORCEPROP 1 LAST BODY_TYPE PLUMBING
J 0
(-1495 -893);
DISPLAY 0.340426 (-1495 -893);
PAINT GREEN (-1495 -893);
DISPLAY INVISIBLE (-1495 -893);
FORCEPROP 2 LAST CDS_LIB mstr_symbols
J 0
(-1450 -850);
PAINT ORANGE (-1450 -850);
DISPLAY INVISIBLE (-1450 -850);
FORCEPROP 1 LAST HDL_POWER P1V05_PCH_STBY
J 0
(-1450 -800);
DISPLAY 0.872340 (-1450 -800);
PAINT GREEN (-1450 -800);
DISPLAY INVISIBLE (-1450 -800);
FORCEPROP 1 LAST VOLTAGE 1.05V
J 0
(-1495 -893);
DISPLAY 0.340426 (-1495 -893);
PAINT SKYBLUE (-1495 -893);
DISPLAY INVISIBLE (-1495 -893);
FORCEADD FERRITE..1
(-1225 -1200);
FORCEPROP 1 LASTPIN (-1325 -1200) $PN 1
J 2
(-1290 -1190);
DISPLAY 0.617021 (-1290 -1190);
PAINT WHITE (-1290 -1190);
FORCEPROP 1 LASTPIN (-1125 -1200) $PN 2
J 0
(-1145 -1190);
DISPLAY 0.617021 (-1145 -1190);
PAINT WHITE (-1145 -1190);
FORCEPROP 1 LAST MATERIAL FB
J 0
(-1170 -1300);
DISPLAY 0.617021 (-1170 -1300);
PAINT SKYBLUE (-1170 -1300);
FORCEPROP 1 LAST PACK_TYPE SM
J 0
(-1145 -1250);
DISPLAY 0.617021 (-1145 -1250);
PAINT SKYBLUE (-1145 -1250);
FORCEPROP 1 LAST VALUE 120
J 2
(-1220 -1300);
DISPLAY 0.617021 (-1220 -1300);
PAINT SKYBLUE (-1220 -1300);
FORCEPROP 1 LAST PART_NUMBER 693286-027
J 0
(-1320 -1085);
DISPLAY 0.617021 (-1320 -1085);
PAINT BLUE (-1320 -1085);
FORCEPROP 1 LAST LOCATION FB2M2
J 0
(-1320 -1145);
DISPLAY 0.617021 (-1320 -1145);
PAINT AQUA (-1320 -1145);
FORCEPROP 1 LAST PATH I69
J 0
(-1320 -1035);
DISPLAY 0.872340 (-1320 -1035);
PAINT PURPLE (-1320 -1035);
DISPLAY INVISIBLE (-1320 -1035);
FORCEPROP 2 LAST CDS_LOCATION FB2M2
J 0
(-1320 -1145);
DISPLAY 0.617021 (-1320 -1145);
PAINT AQUA (-1320 -1145);
DISPLAY INVISIBLE (-1320 -1145);
FORCEPROP 2 LAST SEC 1
J 0
(-1300 -975);
DISPLAY 0.680851 (-1300 -975);
PAINT MONO (-1300 -975);
DISPLAY INVISIBLE (-1300 -975);
FORCEPROP 2 LAST CDS_LIB mstr_discrete
J 0
(-1225 -1200);
PAINT ORANGE (-1225 -1200);
DISPLAY INVISIBLE (-1225 -1200);
FORCEPROP 2 LAST BOM_COST SB
J 0
(-1325 -1050);
DISPLAY 1.659574 (-1325 -1050);
PAINT WHITE (-1325 -1050);
DISPLAY INVISIBLE (-1325 -1050);
FORCEPROP 2 LAST SEC_TYPE SM
J 0
(-1300 -975);
DISPLAY 1.021277 (-1300 -975);
PAINT ORANGE (-1300 -975);
DISPLAY INVISIBLE (-1300 -975);
FORCEPROP 2 LAST ROOM SB_FILTER_VM26
J 0
(-1325 -1050);
DISPLAY 1.659574 (-1325 -1050);
PAINT WHITE (-1325 -1050);
DISPLAY INVISIBLE (-1325 -1050);
FORCEADD P1V05_PCH_STBY..1
(-4300 -500);
FORCEPROP 3 LASTPIN (-4300 -550) SIG_NAME P1V05_PCH_STBY\g
J 0
(-4290 -540);
DISPLAY 0.659574 (-4290 -540);
PAINT MONO (-4290 -540);
DISPLAY INVISIBLE (-4290 -540);
FORCEPROP 1 LAST PATH I7
J 0
(-4250 -475);
DISPLAY 0.872340 (-4250 -475);
PAINT AQUA (-4250 -475);
DISPLAY INVISIBLE (-4250 -475);
FORCEPROP 1 LAST BODY_TYPE PLUMBING
J 0
(-4345 -543);
DISPLAY 0.340426 (-4345 -543);
PAINT GREEN (-4345 -543);
DISPLAY INVISIBLE (-4345 -543);
FORCEPROP 2 LAST CDS_LIB mstr_symbols
J 0
(-4300 -500);
PAINT ORANGE (-4300 -500);
DISPLAY INVISIBLE (-4300 -500);
FORCEPROP 1 LAST HDL_POWER P1V05_PCH_STBY
J 0
(-4300 -450);
DISPLAY 0.872340 (-4300 -450);
PAINT GREEN (-4300 -450);
DISPLAY INVISIBLE (-4300 -450);
FORCEPROP 1 LAST VOLTAGE 1.05V
J 0
(-4345 -543);
DISPLAY 0.340426 (-4345 -543);
PAINT SKYBLUE (-4345 -543);
DISPLAY INVISIBLE (-4345 -543);
FORCEADD P1V05_PCH_STBY..1
(-1450 -2725);
FORCEPROP 3 LASTPIN (-1450 -2775) SIG_NAME P1V05_PCH_STBY\g
J 0
(-1440 -2765);
DISPLAY 0.659574 (-1440 -2765);
PAINT MONO (-1440 -2765);
DISPLAY INVISIBLE (-1440 -2765);
FORCEPROP 1 LAST PATH I70
J 0
(-1400 -2700);
DISPLAY 0.872340 (-1400 -2700);
PAINT AQUA (-1400 -2700);
DISPLAY INVISIBLE (-1400 -2700);
FORCEPROP 1 LAST BODY_TYPE PLUMBING
J 0
(-1495 -2768);
DISPLAY 0.340426 (-1495 -2768);
PAINT GREEN (-1495 -2768);
DISPLAY INVISIBLE (-1495 -2768);
FORCEPROP 2 LAST CDS_LIB mstr_symbols
J 0
(-1450 -2725);
PAINT ORANGE (-1450 -2725);
DISPLAY INVISIBLE (-1450 -2725);
FORCEPROP 1 LAST HDL_POWER P1V05_PCH_STBY
J 0
(-1450 -2675);
DISPLAY 0.872340 (-1450 -2675);
PAINT GREEN (-1450 -2675);
DISPLAY INVISIBLE (-1450 -2675);
FORCEPROP 1 LAST VOLTAGE 1.05V
J 0
(-1495 -2768);
DISPLAY 0.340426 (-1495 -2768);
PAINT SKYBLUE (-1495 -2768);
DISPLAY INVISIBLE (-1495 -2768);
FORCEADD INDUCTOR..1
(-1250 -3100);
FORCEPROP 1 LASTPIN (-1350 -3100) $PN 1
J 0
(-1350 -3090);
DISPLAY 0.617021 (-1350 -3090);
PAINT WHITE (-1350 -3090);
FORCEPROP 1 LASTPIN (-1150 -3100) $PN 2
J 2
(-1140 -3090);
DISPLAY 0.617021 (-1140 -3090);
PAINT WHITE (-1140 -3090);
FORCEPROP 1 LAST MATERIAL IND
J 0
(-1235 -3185);
DISPLAY 0.617021 (-1235 -3185);
PAINT SKYBLUE (-1235 -3185);
FORCEPROP 1 LAST PACK_TYPE SMT
J 0
(-1135 -3185);
DISPLAY 0.617021 (-1135 -3185);
PAINT SKYBLUE (-1135 -3185);
FORCEPROP 1 LAST PART_NUMBER 721891-082
J 0
(-1350 -3000);
DISPLAY 0.617021 (-1350 -3000);
PAINT BLUE (-1350 -3000);
FORCEPROP 1 LAST LOCATION L2M1
J 0
(-1350 -3050);
DISPLAY 0.617021 (-1350 -3050);
PAINT AQUA (-1350 -3050);
FORCEPROP 1 LAST VALUE 0.022UH
J 2
(-1255 -3185);
DISPLAY 0.617021 (-1255 -3185);
PAINT SKYBLUE (-1255 -3185);
FORCEPROP 1 LAST PATH I71
J 0
(-1350 -2950);
DISPLAY 0.978723 (-1350 -2950);
PAINT ORANGE (-1350 -2950);
DISPLAY INVISIBLE (-1350 -2950);
FORCEPROP 2 LAST CDS_LOCATION L2M1
J 0
(-1350 -3050);
DISPLAY 0.617021 (-1350 -3050);
PAINT AQUA (-1350 -3050);
DISPLAY INVISIBLE (-1350 -3050);
FORCEPROP 2 LAST SEC 1
J 0
(-1350 -2900);
PAINT MONO (-1350 -2900);
DISPLAY INVISIBLE (-1350 -2900);
FORCEPROP 2 LAST SEC_TYPE SMT
J 0
(-1350 -2900);
DISPLAY 1.021277 (-1350 -2900);
PAINT ORANGE (-1350 -2900);
DISPLAY INVISIBLE (-1350 -2900);
FORCEPROP 2 LAST CDS_LIB mstr_discrete
J 0
(-1250 -3100);
PAINT ORANGE (-1250 -3100);
DISPLAY INVISIBLE (-1250 -3100);
FORCEPROP 2 LAST BOM_COST SB
J 0
(-1350 -2950);
DISPLAY 1.659574 (-1350 -2950);
PAINT WHITE (-1350 -2950);
DISPLAY INVISIBLE (-1350 -2950);
FORCEPROP 2 LAST ROOM SB_FILTER_KR_PLL
J 0
(-1350 -2950);
DISPLAY 1.659574 (-1350 -2950);
PAINT WHITE (-1350 -2950);
DISPLAY INVISIBLE (-1350 -2950);
FORCEADD P1V05_PCH_STBY_VCCA_PLL0..1
(-2575 -1675);
FORCEPROP 3 LASTPIN (-2575 -1725) SIG_NAME P1V05_PCH_STBY_VCCA_PLL0\g
J 0
(-2565 -1715);
DISPLAY 0.659574 (-2565 -1715);
PAINT MONO (-2565 -1715);
DISPLAY INVISIBLE (-2565 -1715);
FORCEPROP 1 LAST PATH I72
J 0
(-2525 -1650);
DISPLAY 0.872340 (-2525 -1650);
PAINT AQUA (-2525 -1650);
DISPLAY INVISIBLE (-2525 -1650);
FORCEPROP 1 LAST BODY_TYPE PLUMBING
J 0
(-2620 -1718);
DISPLAY 0.340426 (-2620 -1718);
PAINT GREEN (-2620 -1718);
DISPLAY INVISIBLE (-2620 -1718);
FORCEPROP 2 LAST CDS_LIB mstr_symbols
J 0
(-2575 -1675);
PAINT ORANGE (-2575 -1675);
DISPLAY INVISIBLE (-2575 -1675);
FORCEPROP 2 LAST BOM_COST SB
J 0
(-2575 -1525);
PAINT MONO (-2575 -1525);
DISPLAY INVISIBLE (-2575 -1525);
FORCEPROP 2 LAST ROOM SB_DECOUPLING
J 0
(-2575 -1575);
DISPLAY 1.361702 (-2575 -1575);
PAINT WHITE (-2575 -1575);
DISPLAY INVISIBLE (-2575 -1575);
FORCEPROP 1 LAST HDL_POWER P1V05_PCH_STBY_VCCA_PLL0
J 1
(-2575 -1625);
DISPLAY 0.872340 (-2575 -1625);
PAINT GREEN (-2575 -1625);
DISPLAY INVISIBLE (-2575 -1625);
FORCEPROP 1 LAST VOLTAGE 1.05V
J 0
(-2620 -1718);
DISPLAY 0.340426 (-2620 -1718);
PAINT SKYBLUE (-2620 -1718);
DISPLAY INVISIBLE (-2620 -1718);
FORCEADD P1V05_PCH_STBY_VCCA_PLL1..1
(-2575 -475);
FORCEPROP 3 LASTPIN (-2575 -525) SIG_NAME P1V05_PCH_STBY_VCCA_PLL1\g
J 0
(-2565 -515);
DISPLAY 0.659574 (-2565 -515);
PAINT MONO (-2565 -515);
DISPLAY INVISIBLE (-2565 -515);
FORCEPROP 1 LAST PATH I73
J 0
(-2525 -450);
DISPLAY 0.872340 (-2525 -450);
PAINT AQUA (-2525 -450);
DISPLAY INVISIBLE (-2525 -450);
FORCEPROP 1 LAST BODY_TYPE PLUMBING
J 0
(-2620 -518);
DISPLAY 0.340426 (-2620 -518);
PAINT GREEN (-2620 -518);
DISPLAY INVISIBLE (-2620 -518);
FORCEPROP 2 LAST CDS_LIB mstr_symbols
J 0
(-2575 -475);
PAINT ORANGE (-2575 -475);
DISPLAY INVISIBLE (-2575 -475);
FORCEPROP 2 LAST BOM_COST SB
J 0
(-2575 -325);
PAINT MONO (-2575 -325);
DISPLAY INVISIBLE (-2575 -325);
FORCEPROP 2 LAST ROOM SB_DECOUPLING
J 0
(-2575 -375);
DISPLAY 1.361702 (-2575 -375);
PAINT WHITE (-2575 -375);
DISPLAY INVISIBLE (-2575 -375);
FORCEPROP 1 LAST HDL_POWER P1V05_PCH_STBY_VCCA_PLL1
J 1
(-2575 -425);
DISPLAY 0.872340 (-2575 -425);
PAINT GREEN (-2575 -425);
DISPLAY INVISIBLE (-2575 -425);
FORCEPROP 1 LAST VOLTAGE 1.05V
J 0
(-2620 -518);
DISPLAY 0.340426 (-2620 -518);
PAINT SKYBLUE (-2620 -518);
DISPLAY INVISIBLE (-2620 -518);
FORCEADD CAP_A..1
R 2
(-1450 -1400);
FORCEPROP 1 LASTPIN (-1450 -1500) $PN 2
J 2
(-1460 -1520);
DISPLAY 0.617021 (-1460 -1520);
PAINT ORANGE (-1460 -1520);
FORCEPROP 1 LASTPIN (-1450 -1300) $PN 1
J 2
(-1460 -1320);
DISPLAY 0.617021 (-1460 -1320);
PAINT ORANGE (-1460 -1320);
FORCEPROP 1 LAST MATERIAL X6S
J 2
(-1500 -1500);
DISPLAY 0.617021 (-1500 -1500);
PAINT SKYBLUE (-1500 -1500);
FORCEPROP 1 LAST PACK_TYPE 0402V
J 2
(-1500 -1600);
DISPLAY 0.617021 (-1500 -1600);
PAINT SKYBLUE (-1500 -1600);
FORCEPROP 1 LAST VALUE 1.0UF
J 2
(-1500 -1350);
DISPLAY 0.617021 (-1500 -1350);
PAINT SKYBLUE (-1500 -1350);
FORCEPROP 1 LAST PART_NUMBER D97712-004
J 2
(-1500 -1550);
DISPLAY 0.617021 (-1500 -1550);
PAINT BLUE (-1500 -1550);
FORCEPROP 1 LAST LOCATION C2M8
J 2
(-1500 -1300);
DISPLAY 0.617021 (-1500 -1300);
PAINT AQUA (-1500 -1300);
FORCEPROP 1 LAST VOLTAGE 6.3V
J 2
(-1500 -1400);
DISPLAY 0.617021 (-1500 -1400);
PAINT SKYBLUE (-1500 -1400);
FORCEPROP 1 LAST TOLERANCE 10%
J 2
(-1500 -1450);
DISPLAY 0.617021 (-1500 -1450);
PAINT SKYBLUE (-1500 -1450);
FORCEPROP 1 LAST PATH I74
J 2
(-1500 -1250);
DISPLAY 0.978723 (-1500 -1250);
PAINT WHITE (-1500 -1250);
DISPLAY INVISIBLE (-1500 -1250);
FORCEPROP 2 LAST SEC 1
J 2
(-1500 -1200);
DISPLAY 0.680851 (-1500 -1200);
PAINT MONO (-1500 -1200);
DISPLAY INVISIBLE (-1500 -1200);
FORCEPROP 2 LAST SEC_TYPE 0402V
J 2
(-1500 -1200);
DISPLAY 1.021277 (-1500 -1200);
PAINT ORANGE (-1500 -1200);
DISPLAY INVISIBLE (-1500 -1200);
FORCEPROP 2 LAST CDS_SEC 1
J 2
(-1500 -1250);
PAINT ORANGE (-1500 -1250);
DISPLAY INVISIBLE (-1500 -1250);
FORCEPROP 2 LAST CDS_LIB dev_discrete
J 2
(-1450 -1400);
PAINT ORANGE (-1450 -1400);
DISPLAY INVISIBLE (-1450 -1400);
FORCEPROP 2 LAST BOM_COST SB
J 2
(-1500 -1250);
DISPLAY 1.659574 (-1500 -1250);
PAINT WHITE (-1500 -1250);
DISPLAY INVISIBLE (-1500 -1250);
FORCEPROP 2 LAST CDS_LOCATION C2M8
J 2
(-1500 -1300);
DISPLAY 0.617021 (-1500 -1300);
PAINT AQUA (-1500 -1300);
DISPLAY INVISIBLE (-1500 -1300);
FORCEPROP 2 LAST ROOM SB_FILTER_VM26
J 2
(-1500 -1250);
DISPLAY 1.659574 (-1500 -1250);
PAINT WHITE (-1500 -1250);
DISPLAY INVISIBLE (-1500 -1250);
FORCEADD GND..1
(-1450 -1750);
FORCEPROP 3 LASTPIN (-1450 -1700) SIG_NAME GND\g
J 0
(-1440 -1690);
DISPLAY 0.659574 (-1440 -1690);
PAINT MONO (-1440 -1690);
DISPLAY INVISIBLE (-1440 -1690);
FORCEPROP 1 LAST PATH I75
J 0
(-1375 -1750);
DISPLAY 0.872340 (-1375 -1750);
PAINT AQUA (-1375 -1750);
DISPLAY INVISIBLE (-1375 -1750);
FORCEPROP 1 LAST BODY_TYPE PLUMBING
J 0
(-1495 -1793);
DISPLAY 0.340426 (-1495 -1793);
PAINT GREEN (-1495 -1793);
DISPLAY INVISIBLE (-1495 -1793);
FORCEPROP 1 LAST SIZE 1B
J 0
(-1375 -1800);
DISPLAY 1.404255 (-1375 -1800);
PAINT AQUA (-1375 -1800);
DISPLAY INVISIBLE (-1375 -1800);
FORCEPROP 2 LAST CDS_LIB mstr_symbols
J 0
(-1450 -1750);
PAINT ORANGE (-1450 -1750);
DISPLAY INVISIBLE (-1450 -1750);
FORCEPROP 1 LAST HDL_POWER GND
J 0
(-1450 -1600);
PAINT GREEN (-1450 -1600);
DISPLAY INVISIBLE (-1450 -1600);
FORCEPROP 1 LAST VOLTAGE 0.0V
J 0
(-1495 -1793);
DISPLAY 0.340426 (-1495 -1793);
PAINT SKYBLUE (-1495 -1793);
DISPLAY INVISIBLE (-1495 -1793);
FORCEADD CAP_A..1
R 2
(950 -1375);
FORCEPROP 1 LASTPIN (950 -1475) $PN 2
J 2
(940 -1495);
DISPLAY 0.617021 (940 -1495);
PAINT ORANGE (940 -1495);
FORCEPROP 1 LASTPIN (950 -1275) $PN 1
J 2
(940 -1295);
DISPLAY 0.617021 (940 -1295);
PAINT ORANGE (940 -1295);
FORCEPROP 1 LAST MATERIAL X6S
J 2
(900 -1475);
DISPLAY 0.617021 (900 -1475);
PAINT SKYBLUE (900 -1475);
FORCEPROP 1 LAST VOLTAGE 6.3V
J 2
(900 -1375);
DISPLAY 0.617021 (900 -1375);
PAINT SKYBLUE (900 -1375);
FORCEPROP 1 LAST PACK_TYPE 0402V
J 2
(900 -1575);
DISPLAY 0.617021 (900 -1575);
PAINT SKYBLUE (900 -1575);
FORCEPROP 1 LAST TOLERANCE 10%
J 2
(900 -1425);
DISPLAY 0.617021 (900 -1425);
PAINT SKYBLUE (900 -1425);
FORCEPROP 1 LAST VALUE 1.0UF
J 2
(900 -1325);
DISPLAY 0.617021 (900 -1325);
PAINT SKYBLUE (900 -1325);
FORCEPROP 1 LAST PART_NUMBER D97712-004
J 2
(900 -1525);
DISPLAY 0.617021 (900 -1525);
PAINT BLUE (900 -1525);
FORCEPROP 1 LAST LOCATION C2M6
J 2
(900 -1275);
DISPLAY 0.617021 (900 -1275);
PAINT AQUA (900 -1275);
FORCEPROP 1 LAST PATH I76
J 2
(900 -1225);
DISPLAY 0.978723 (900 -1225);
PAINT WHITE (900 -1225);
DISPLAY INVISIBLE (900 -1225);
FORCEPROP 2 LAST SEC 1
J 2
(900 -1175);
DISPLAY 0.680851 (900 -1175);
PAINT MONO (900 -1175);
DISPLAY INVISIBLE (900 -1175);
FORCEPROP 2 LAST SEC_TYPE 0402V
J 2
(900 -1175);
DISPLAY 1.021277 (900 -1175);
PAINT ORANGE (900 -1175);
DISPLAY INVISIBLE (900 -1175);
FORCEPROP 2 LAST CDS_SEC 1
J 2
(900 -1225);
PAINT ORANGE (900 -1225);
DISPLAY INVISIBLE (900 -1225);
FORCEPROP 2 LAST CDS_LIB dev_discrete
J 2
(950 -1375);
PAINT ORANGE (950 -1375);
DISPLAY INVISIBLE (950 -1375);
FORCEPROP 2 LAST BOM_COST SB
J 2
(900 -1225);
DISPLAY 1.659574 (900 -1225);
PAINT WHITE (900 -1225);
DISPLAY INVISIBLE (900 -1225);
FORCEPROP 2 LAST CDS_LOCATION C2M6
J 2
(900 -1275);
DISPLAY 0.617021 (900 -1275);
PAINT AQUA (900 -1275);
DISPLAY INVISIBLE (900 -1275);
FORCEPROP 2 LAST ROOM SB_FILTER_VM20
J 2
(900 -1225);
DISPLAY 1.659574 (900 -1225);
PAINT WHITE (900 -1225);
DISPLAY INVISIBLE (900 -1225);
FORCEADD GND..1
(950 -1725);
FORCEPROP 3 LASTPIN (950 -1675) SIG_NAME GND\g
J 0
(960 -1665);
DISPLAY 0.659574 (960 -1665);
PAINT MONO (960 -1665);
DISPLAY INVISIBLE (960 -1665);
FORCEPROP 1 LAST PATH I77
J 0
(1025 -1725);
DISPLAY 0.872340 (1025 -1725);
PAINT AQUA (1025 -1725);
DISPLAY INVISIBLE (1025 -1725);
FORCEPROP 1 LAST BODY_TYPE PLUMBING
J 0
(905 -1768);
DISPLAY 0.340426 (905 -1768);
PAINT GREEN (905 -1768);
DISPLAY INVISIBLE (905 -1768);
FORCEPROP 2 LAST CDS_LIB mstr_symbols
J 0
(950 -1725);
PAINT ORANGE (950 -1725);
DISPLAY INVISIBLE (950 -1725);
FORCEPROP 1 LAST SIZE 1B
J 0
(1025 -1775);
DISPLAY 1.404255 (1025 -1775);
PAINT AQUA (1025 -1775);
DISPLAY INVISIBLE (1025 -1775);
FORCEPROP 1 LAST HDL_POWER GND
J 0
(950 -1575);
PAINT GREEN (950 -1575);
DISPLAY INVISIBLE (950 -1575);
FORCEPROP 1 LAST VOLTAGE 0.0V
J 0
(905 -1768);
DISPLAY 0.340426 (905 -1768);
PAINT SKYBLUE (905 -1768);
DISPLAY INVISIBLE (905 -1768);
FORCEADD CAP_A..1
R 2
(-1450 -3300);
FORCEPROP 1 LASTPIN (-1450 -3400) $PN 2
J 2
(-1460 -3420);
DISPLAY 0.617021 (-1460 -3420);
PAINT ORANGE (-1460 -3420);
FORCEPROP 1 LASTPIN (-1450 -3200) $PN 1
J 2
(-1460 -3220);
DISPLAY 0.617021 (-1460 -3220);
PAINT ORANGE (-1460 -3220);
FORCEPROP 1 LAST VOLTAGE 6.3V
J 2
(-1500 -3300);
DISPLAY 0.617021 (-1500 -3300);
PAINT SKYBLUE (-1500 -3300);
FORCEPROP 1 LAST PACK_TYPE 0402V
J 2
(-1500 -3500);
DISPLAY 0.617021 (-1500 -3500);
PAINT SKYBLUE (-1500 -3500);
FORCEPROP 1 LAST TOLERANCE 10%
J 2
(-1500 -3350);
DISPLAY 0.617021 (-1500 -3350);
PAINT SKYBLUE (-1500 -3350);
FORCEPROP 1 LAST VALUE 1.0UF
J 2
(-1500 -3250);
DISPLAY 0.617021 (-1500 -3250);
PAINT SKYBLUE (-1500 -3250);
FORCEPROP 1 LAST PART_NUMBER D97712-004
J 2
(-1500 -3450);
DISPLAY 0.617021 (-1500 -3450);
PAINT BLUE (-1500 -3450);
FORCEPROP 1 LAST LOCATION C2M25
J 2
(-1500 -3200);
DISPLAY 0.617021 (-1500 -3200);
PAINT AQUA (-1500 -3200);
FORCEPROP 1 LAST MATERIAL X6S
J 2
(-1500 -3400);
DISPLAY 0.617021 (-1500 -3400);
PAINT SKYBLUE (-1500 -3400);
FORCEPROP 1 LAST PATH I78
J 2
(-1500 -3150);
DISPLAY 0.978723 (-1500 -3150);
PAINT WHITE (-1500 -3150);
DISPLAY INVISIBLE (-1500 -3150);
FORCEPROP 2 LAST SEC 1
J 2
(-1500 -3100);
DISPLAY 0.680851 (-1500 -3100);
PAINT MONO (-1500 -3100);
DISPLAY INVISIBLE (-1500 -3100);
FORCEPROP 2 LAST SEC_TYPE 0402V
J 2
(-1500 -3100);
DISPLAY 1.021277 (-1500 -3100);
PAINT ORANGE (-1500 -3100);
DISPLAY INVISIBLE (-1500 -3100);
FORCEPROP 2 LAST CDS_SEC 1
J 2
(-1500 -3150);
PAINT ORANGE (-1500 -3150);
DISPLAY INVISIBLE (-1500 -3150);
FORCEPROP 2 LAST CDS_LIB dev_discrete
J 2
(-1450 -3300);
PAINT ORANGE (-1450 -3300);
DISPLAY INVISIBLE (-1450 -3300);
FORCEPROP 2 LAST BOM_COST SB
J 2
(-1500 -3150);
DISPLAY 1.659574 (-1500 -3150);
PAINT WHITE (-1500 -3150);
DISPLAY INVISIBLE (-1500 -3150);
FORCEPROP 2 LAST ROOM SB_FILTER_KR_PLL
J 2
(-1500 -3150);
DISPLAY 1.659574 (-1500 -3150);
PAINT WHITE (-1500 -3150);
DISPLAY INVISIBLE (-1500 -3150);
FORCEPROP 2 LAST CDS_LOCATION C2M25
J 2
(-1500 -3200);
DISPLAY 0.617021 (-1500 -3200);
PAINT AQUA (-1500 -3200);
DISPLAY INVISIBLE (-1500 -3200);
FORCEADD GND..1
(-1450 -3625);
FORCEPROP 3 LASTPIN (-1450 -3575) SIG_NAME GND\g
J 0
(-1440 -3565);
DISPLAY 0.659574 (-1440 -3565);
PAINT MONO (-1440 -3565);
DISPLAY INVISIBLE (-1440 -3565);
FORCEPROP 1 LAST PATH I79
J 0
(-1375 -3625);
DISPLAY 0.872340 (-1375 -3625);
PAINT AQUA (-1375 -3625);
DISPLAY INVISIBLE (-1375 -3625);
FORCEPROP 1 LAST BODY_TYPE PLUMBING
J 0
(-1495 -3668);
DISPLAY 0.340426 (-1495 -3668);
PAINT GREEN (-1495 -3668);
DISPLAY INVISIBLE (-1495 -3668);
FORCEPROP 1 LAST SIZE 1B
J 0
(-1375 -3675);
DISPLAY 1.404255 (-1375 -3675);
PAINT AQUA (-1375 -3675);
DISPLAY INVISIBLE (-1375 -3675);
FORCEPROP 2 LAST CDS_LIB mstr_symbols
J 0
(-1450 -3625);
PAINT ORANGE (-1450 -3625);
DISPLAY INVISIBLE (-1450 -3625);
FORCEPROP 1 LAST HDL_POWER GND
J 0
(-1450 -3475);
PAINT GREEN (-1450 -3475);
DISPLAY INVISIBLE (-1450 -3475);
FORCEPROP 1 LAST VOLTAGE 0.0V
J 0
(-1495 -3668);
DISPLAY 0.340426 (-1495 -3668);
PAINT SKYBLUE (-1495 -3668);
DISPLAY INVISIBLE (-1495 -3668);
FORCEADD FERRITE..1
(-4050 -850);
FORCEPROP 1 LASTPIN (-4150 -850) $PN 1
J 2
(-4115 -840);
DISPLAY 0.617021 (-4115 -840);
PAINT WHITE (-4115 -840);
FORCEPROP 1 LASTPIN (-3950 -850) $PN 2
J 0
(-3970 -840);
DISPLAY 0.617021 (-3970 -840);
PAINT WHITE (-3970 -840);
FORCEPROP 1 LAST MATERIAL FB
J 0
(-3995 -950);
DISPLAY 0.617021 (-3995 -950);
PAINT SKYBLUE (-3995 -950);
FORCEPROP 1 LAST PACK_TYPE SM
J 0
(-3970 -900);
DISPLAY 0.617021 (-3970 -900);
PAINT SKYBLUE (-3970 -900);
FORCEPROP 1 LAST PART_NUMBER 693286-027
J 0
(-4145 -735);
DISPLAY 0.617021 (-4145 -735);
PAINT BLUE (-4145 -735);
FORCEPROP 1 LAST LOCATION FB3M1
J 0
(-4145 -795);
DISPLAY 0.617021 (-4145 -795);
PAINT AQUA (-4145 -795);
FORCEPROP 1 LAST VALUE 120
J 2
(-4045 -950);
DISPLAY 0.617021 (-4045 -950);
PAINT SKYBLUE (-4045 -950);
FORCEPROP 1 LAST PATH I8
J 0
(-4145 -685);
DISPLAY 0.872340 (-4145 -685);
PAINT PURPLE (-4145 -685);
DISPLAY INVISIBLE (-4145 -685);
FORCEPROP 2 LAST CDS_LOCATION FB3M1
J 0
(-4145 -795);
DISPLAY 0.617021 (-4145 -795);
PAINT AQUA (-4145 -795);
DISPLAY INVISIBLE (-4145 -795);
FORCEPROP 2 LAST SEC 1
J 0
(-4125 -625);
PAINT MONO (-4125 -625);
DISPLAY INVISIBLE (-4125 -625);
FORCEPROP 2 LAST SEC_TYPE SM
J 0
(-4125 -625);
DISPLAY 1.021277 (-4125 -625);
PAINT ORANGE (-4125 -625);
DISPLAY INVISIBLE (-4125 -625);
FORCEPROP 2 LAST BOM_COST SB
J 0
(-4150 -700);
DISPLAY 1.659574 (-4150 -700);
PAINT WHITE (-4150 -700);
DISPLAY INVISIBLE (-4150 -700);
FORCEPROP 2 LAST CDS_LIB mstr_discrete
J 0
(-4050 -850);
PAINT ORANGE (-4050 -850);
DISPLAY INVISIBLE (-4050 -850);
FORCEPROP 2 LAST ROOM SB_FILTER_PLL0
J 0
(-4150 -700);
DISPLAY 1.659574 (-4150 -700);
PAINT WHITE (-4150 -700);
DISPLAY INVISIBLE (-4150 -700);
FORCEADD CAP_A..1
(1400 -3275);
FORCEPROP 1 LASTPIN (1400 -3175) $PN 1
J 0
(1410 -3195);
DISPLAY 0.617021 (1410 -3195);
PAINT ORANGE (1410 -3195);
FORCEPROP 1 LASTPIN (1400 -3375) $PN 2
J 0
(1410 -3395);
DISPLAY 0.617021 (1410 -3395);
PAINT ORANGE (1410 -3395);
FORCEPROP 1 LAST MATERIAL X6S
J 0
(1450 -3375);
DISPLAY 0.617021 (1450 -3375);
PAINT SKYBLUE (1450 -3375);
FORCEPROP 1 LAST VOLTAGE 6.3V
J 0
(1450 -3275);
DISPLAY 0.617021 (1450 -3275);
PAINT SKYBLUE (1450 -3275);
FORCEPROP 1 LAST PACK_TYPE 0402V
J 0
(1450 -3475);
DISPLAY 0.617021 (1450 -3475);
PAINT SKYBLUE (1450 -3475);
FORCEPROP 1 LAST TOLERANCE 10%
J 0
(1450 -3325);
DISPLAY 0.617021 (1450 -3325);
PAINT SKYBLUE (1450 -3325);
FORCEPROP 1 LAST VALUE 1.0UF
J 0
(1450 -3225);
DISPLAY 0.617021 (1450 -3225);
PAINT SKYBLUE (1450 -3225);
FORCEPROP 1 LAST PART_NUMBER D97712-004
J 0
(1450 -3425);
DISPLAY 0.617021 (1450 -3425);
PAINT BLUE (1450 -3425);
FORCEPROP 1 LAST LOCATION C3M29
J 0
(1450 -3175);
DISPLAY 0.617021 (1450 -3175);
PAINT AQUA (1450 -3175);
FORCEPROP 1 LAST PATH I80
J 0
(1450 -3125);
DISPLAY 0.978723 (1450 -3125);
PAINT WHITE (1450 -3125);
DISPLAY INVISIBLE (1450 -3125);
FORCEPROP 2 LAST CDS_LOCATION C3M29
J 0
(1450 -3175);
DISPLAY 0.617021 (1450 -3175);
PAINT AQUA (1450 -3175);
DISPLAY INVISIBLE (1450 -3175);
FORCEPROP 2 LAST BOM_COST SB
J 0
(1450 -3125);
DISPLAY 1.659574 (1450 -3125);
PAINT WHITE (1450 -3125);
DISPLAY INVISIBLE (1450 -3125);
FORCEPROP 2 LAST CDS_LIB dev_discrete
J 0
(1400 -3275);
PAINT ORANGE (1400 -3275);
DISPLAY INVISIBLE (1400 -3275);
FORCEPROP 2 LAST CDS_SEC 1
J 0
(1450 -3125);
PAINT ORANGE (1450 -3125);
DISPLAY INVISIBLE (1450 -3125);
FORCEPROP 2 LAST SEC_TYPE 0402V
J 0
(1450 -3075);
DISPLAY 1.021277 (1450 -3075);
PAINT ORANGE (1450 -3075);
DISPLAY INVISIBLE (1450 -3075);
FORCEPROP 2 LAST SEC 1
J 0
(1450 -3075);
DISPLAY 0.680851 (1450 -3075);
PAINT MONO (1450 -3075);
DISPLAY INVISIBLE (1450 -3075);
FORCEPROP 2 LAST ROOM SB_FILTER_ISCLK
J 0
(1450 -3125);
DISPLAY 1.659574 (1450 -3125);
PAINT WHITE (1450 -3125);
DISPLAY INVISIBLE (1450 -3125);
FORCEADD CAP..1
(1700 -3275);
FORCEPROP 1 LASTPIN (1700 -3175) $PN 1
J 0
(1710 -3195);
DISPLAY 0.617021 (1710 -3195);
PAINT ORANGE (1710 -3195);
FORCEPROP 1 LASTPIN (1700 -3375) $PN 2
J 0
(1710 -3395);
DISPLAY 0.617021 (1710 -3395);
PAINT ORANGE (1710 -3395);
FORCEPROP 1 LAST MATERIAL X6S
J 0
(1750 -3375);
DISPLAY 0.617021 (1750 -3375);
PAINT SKYBLUE (1750 -3375);
FORCEPROP 1 LAST VOLTAGE 4V
J 0
(1750 -3275);
DISPLAY 0.617021 (1750 -3275);
PAINT SKYBLUE (1750 -3275);
FORCEPROP 1 LAST PACK_TYPE 0603LF
J 0
(1750 -3475);
DISPLAY 0.617021 (1750 -3475);
PAINT SKYBLUE (1750 -3475);
FORCEPROP 1 LAST TOLERANCE 20%
J 0
(1750 -3325);
DISPLAY 0.617021 (1750 -3325);
PAINT SKYBLUE (1750 -3325);
FORCEPROP 1 LAST VALUE 10UF
J 0
(1750 -3225);
DISPLAY 0.617021 (1750 -3225);
PAINT SKYBLUE (1750 -3225);
FORCEPROP 1 LAST PART_NUMBER E15431-001
J 0
(1750 -3425);
DISPLAY 0.617021 (1750 -3425);
PAINT BLUE (1750 -3425);
FORCEPROP 1 LAST LOCATION C3M24
J 0
(1750 -3175);
DISPLAY 0.617021 (1750 -3175);
PAINT AQUA (1750 -3175);
FORCEPROP 2 LAST CDS_LOCATION C3M24
J 0
(1750 -3175);
DISPLAY 0.617021 (1750 -3175);
PAINT AQUA (1750 -3175);
DISPLAY INVISIBLE (1750 -3175);
FORCEPROP 2 LAST SEC 1
J 0
(1750 -3075);
DISPLAY 0.680851 (1750 -3075);
PAINT MONO (1750 -3075);
DISPLAY INVISIBLE (1750 -3075);
FORCEPROP 2 LAST CDS_LIB mstr_discrete
J 0
(1700 -3275);
PAINT ORANGE (1700 -3275);
DISPLAY INVISIBLE (1700 -3275);
FORCEPROP 2 LAST SEC_TYPE 0603LF
J 0
(1750 -3075);
DISPLAY 1.021277 (1750 -3075);
PAINT ORANGE (1750 -3075);
DISPLAY INVISIBLE (1750 -3075);
FORCEPROP 2 LAST BOM_COST SB
J 0
(1750 -3125);
DISPLAY 1.659574 (1750 -3125);
PAINT WHITE (1750 -3125);
DISPLAY INVISIBLE (1750 -3125);
FORCEPROP 0 LAST CDS_SEC 1
J 0
(1750 -3125);
PAINT ORANGE (1750 -3125);
DISPLAY INVISIBLE (1750 -3125);
FORCEPROP 1 LAST PATH I81
J 0
(1750 -3125);
DISPLAY 0.978723 (1750 -3125);
PAINT WHITE (1750 -3125);
DISPLAY INVISIBLE (1750 -3125);
FORCEPROP 2 LAST ROOM SB_FILTER_ISCLK
J 0
(1750 -3125);
DISPLAY 1.659574 (1750 -3125);
PAINT WHITE (1750 -3125);
DISPLAY INVISIBLE (1750 -3125);
FORCEADD CAP..1
(-2550 -3600);
FORCEPROP 1 LASTPIN (-2550 -3500) $PN 1
J 0
(-2540 -3520);
DISPLAY 0.617021 (-2540 -3520);
PAINT ORANGE (-2540 -3520);
FORCEPROP 1 LASTPIN (-2550 -3700) $PN 2
J 0
(-2540 -3720);
DISPLAY 0.617021 (-2540 -3720);
PAINT ORANGE (-2540 -3720);
FORCEPROP 1 LAST MATERIAL X6S
J 0
(-2500 -3700);
DISPLAY 0.617021 (-2500 -3700);
PAINT SKYBLUE (-2500 -3700);
FORCEPROP 1 LAST VOLTAGE 4V
J 0
(-2500 -3600);
DISPLAY 0.617021 (-2500 -3600);
PAINT SKYBLUE (-2500 -3600);
FORCEPROP 1 LAST PACK_TYPE 0603LF
J 0
(-2500 -3800);
DISPLAY 0.617021 (-2500 -3800);
PAINT SKYBLUE (-2500 -3800);
FORCEPROP 1 LAST TOLERANCE 20%
J 0
(-2500 -3650);
DISPLAY 0.617021 (-2500 -3650);
PAINT SKYBLUE (-2500 -3650);
FORCEPROP 1 LAST VALUE 10UF
J 0
(-2500 -3550);
DISPLAY 0.617021 (-2500 -3550);
PAINT SKYBLUE (-2500 -3550);
FORCEPROP 1 LAST PART_NUMBER E15431-001
J 0
(-2500 -3750);
DISPLAY 0.617021 (-2500 -3750);
PAINT BLUE (-2500 -3750);
FORCEPROP 1 LAST LOCATION C3M23
J 0
(-2500 -3500);
DISPLAY 0.617021 (-2500 -3500);
PAINT AQUA (-2500 -3500);
FORCEPROP 2 LAST CDS_LOCATION C3M23
J 0
(-2500 -3500);
DISPLAY 0.617021 (-2500 -3500);
PAINT AQUA (-2500 -3500);
DISPLAY INVISIBLE (-2500 -3500);
FORCEPROP 2 LAST SEC 1
J 0
(-2500 -3400);
PAINT MONO (-2500 -3400);
DISPLAY INVISIBLE (-2500 -3400);
FORCEPROP 2 LAST SEC_TYPE 0603LF
J 0
(-2500 -3400);
DISPLAY 1.021277 (-2500 -3400);
PAINT ORANGE (-2500 -3400);
DISPLAY INVISIBLE (-2500 -3400);
FORCEPROP 2 LAST CDS_LIB mstr_discrete
J 0
(-2550 -3600);
PAINT ORANGE (-2550 -3600);
DISPLAY INVISIBLE (-2550 -3600);
FORCEPROP 2 LAST BOM_COST SB
J 0
(-2500 -3450);
DISPLAY 1.659574 (-2500 -3450);
PAINT WHITE (-2500 -3450);
DISPLAY INVISIBLE (-2500 -3450);
FORCEPROP 0 LAST CDS_SEC 1
J 0
(-2500 -3450);
PAINT ORANGE (-2500 -3450);
DISPLAY INVISIBLE (-2500 -3450);
FORCEPROP 1 LAST PATH I82
J 0
(-2500 -3450);
DISPLAY 0.978723 (-2500 -3450);
PAINT WHITE (-2500 -3450);
DISPLAY INVISIBLE (-2500 -3450);
FORCEPROP 2 LAST ROOM SB_FILTER_XTAL
J 0
(-2500 -3450);
DISPLAY 1.659574 (-2500 -3450);
PAINT WHITE (-2500 -3450);
DISPLAY INVISIBLE (-2500 -3450);
FORCEADD CAP_A..1
(-3400 -3550);
FORCEPROP 1 LASTPIN (-3400 -3650) $PN 2
J 0
(-3390 -3670);
DISPLAY 0.617021 (-3390 -3670);
PAINT ORANGE (-3390 -3670);
FORCEPROP 1 LASTPIN (-3400 -3450) $PN 1
J 0
(-3390 -3470);
DISPLAY 0.617021 (-3390 -3470);
PAINT ORANGE (-3390 -3470);
FORCEPROP 1 LAST MATERIAL X6S
J 0
(-3350 -3650);
DISPLAY 0.617021 (-3350 -3650);
PAINT SKYBLUE (-3350 -3650);
FORCEPROP 1 LAST VOLTAGE 6.3V
J 0
(-3350 -3550);
DISPLAY 0.617021 (-3350 -3550);
PAINT SKYBLUE (-3350 -3550);
FORCEPROP 1 LAST PACK_TYPE 0402V
J 0
(-3350 -3750);
DISPLAY 0.617021 (-3350 -3750);
PAINT SKYBLUE (-3350 -3750);
FORCEPROP 1 LAST TOLERANCE 10%
J 0
(-3350 -3600);
DISPLAY 0.617021 (-3350 -3600);
PAINT SKYBLUE (-3350 -3600);
FORCEPROP 1 LAST VALUE 1.0UF
J 0
(-3350 -3500);
DISPLAY 0.617021 (-3350 -3500);
PAINT SKYBLUE (-3350 -3500);
FORCEPROP 1 LAST PART_NUMBER D97712-004
J 0
(-3350 -3700);
DISPLAY 0.617021 (-3350 -3700);
PAINT BLUE (-3350 -3700);
FORCEPROP 1 LAST LOCATION C3M27
J 0
(-3350 -3450);
DISPLAY 0.617021 (-3350 -3450);
PAINT AQUA (-3350 -3450);
FORCEPROP 2 LAST SEC 1
J 0
(-3350 -3350);
DISPLAY 0.680851 (-3350 -3350);
PAINT MONO (-3350 -3350);
DISPLAY INVISIBLE (-3350 -3350);
FORCEPROP 2 LAST SEC_TYPE 0402V
J 0
(-3350 -3350);
DISPLAY 1.021277 (-3350 -3350);
PAINT ORANGE (-3350 -3350);
DISPLAY INVISIBLE (-3350 -3350);
FORCEPROP 2 LAST CDS_SEC 1
J 0
(-3350 -3400);
PAINT ORANGE (-3350 -3400);
DISPLAY INVISIBLE (-3350 -3400);
FORCEPROP 2 LAST CDS_LIB dev_discrete
J 0
(-3400 -3550);
PAINT ORANGE (-3400 -3550);
DISPLAY INVISIBLE (-3400 -3550);
FORCEPROP 2 LAST BOM_COST SB
J 0
(-3350 -3400);
DISPLAY 1.659574 (-3350 -3400);
PAINT WHITE (-3350 -3400);
DISPLAY INVISIBLE (-3350 -3400);
FORCEPROP 2 LAST CDS_LOCATION C3M27
J 0
(-3350 -3450);
DISPLAY 0.617021 (-3350 -3450);
PAINT AQUA (-3350 -3450);
DISPLAY INVISIBLE (-3350 -3450);
FORCEPROP 1 LAST PATH I83
J 0
(-3350 -3400);
DISPLAY 0.978723 (-3350 -3400);
PAINT WHITE (-3350 -3400);
DISPLAY INVISIBLE (-3350 -3400);
FORCEPROP 2 LAST ROOM SB_FILTER_XTAL
J 0
(-3350 -3400);
DISPLAY 1.659574 (-3350 -3400);
PAINT WHITE (-3350 -3400);
DISPLAY INVISIBLE (-3350 -3400);
FORCEADD CAP_A..1
(-3425 -2250);
FORCEPROP 1 LASTPIN (-3425 -2150) $PN 1
J 0
(-3415 -2170);
DISPLAY 0.617021 (-3415 -2170);
PAINT ORANGE (-3415 -2170);
FORCEPROP 1 LASTPIN (-3425 -2350) $PN 2
J 0
(-3415 -2370);
DISPLAY 0.617021 (-3415 -2370);
PAINT ORANGE (-3415 -2370);
FORCEPROP 1 LAST VOLTAGE 6.3V
J 0
(-3375 -2250);
DISPLAY 0.617021 (-3375 -2250);
PAINT SKYBLUE (-3375 -2250);
FORCEPROP 1 LAST PACK_TYPE 0402V
J 0
(-3375 -2450);
DISPLAY 0.617021 (-3375 -2450);
PAINT SKYBLUE (-3375 -2450);
FORCEPROP 1 LAST TOLERANCE 10%
J 0
(-3375 -2300);
DISPLAY 0.617021 (-3375 -2300);
PAINT SKYBLUE (-3375 -2300);
FORCEPROP 1 LAST VALUE 1.0UF
J 0
(-3375 -2200);
DISPLAY 0.617021 (-3375 -2200);
PAINT SKYBLUE (-3375 -2200);
FORCEPROP 1 LAST PART_NUMBER D97712-004
J 0
(-3375 -2400);
DISPLAY 0.617021 (-3375 -2400);
PAINT BLUE (-3375 -2400);
FORCEPROP 1 LAST LOCATION C3M20
J 0
(-3375 -2150);
DISPLAY 0.617021 (-3375 -2150);
PAINT AQUA (-3375 -2150);
FORCEPROP 1 LAST MATERIAL X6S
J 0
(-3375 -2350);
DISPLAY 0.617021 (-3375 -2350);
PAINT SKYBLUE (-3375 -2350);
FORCEPROP 1 LAST PATH I84
J 0
(-3375 -2100);
DISPLAY 0.978723 (-3375 -2100);
PAINT WHITE (-3375 -2100);
DISPLAY INVISIBLE (-3375 -2100);
FORCEPROP 2 LAST CDS_LOCATION C3M20
J 0
(-3375 -2150);
DISPLAY 0.617021 (-3375 -2150);
PAINT AQUA (-3375 -2150);
DISPLAY INVISIBLE (-3375 -2150);
FORCEPROP 2 LAST BOM_COST SB
J 0
(-3375 -2100);
DISPLAY 1.659574 (-3375 -2100);
PAINT WHITE (-3375 -2100);
DISPLAY INVISIBLE (-3375 -2100);
FORCEPROP 2 LAST CDS_LIB dev_discrete
J 0
(-3425 -2250);
PAINT ORANGE (-3425 -2250);
DISPLAY INVISIBLE (-3425 -2250);
FORCEPROP 2 LAST CDS_SEC 1
J 0
(-3375 -2100);
PAINT ORANGE (-3375 -2100);
DISPLAY INVISIBLE (-3375 -2100);
FORCEPROP 2 LAST SEC_TYPE 0402V
J 0
(-3375 -2050);
DISPLAY 1.021277 (-3375 -2050);
PAINT ORANGE (-3375 -2050);
DISPLAY INVISIBLE (-3375 -2050);
FORCEPROP 2 LAST SEC 1
J 0
(-3375 -2050);
DISPLAY 0.680851 (-3375 -2050);
PAINT MONO (-3375 -2050);
DISPLAY INVISIBLE (-3375 -2050);
FORCEPROP 2 LAST ROOM SB_FILTER_PLL1
J 0
(-3375 -2100);
DISPLAY 1.659574 (-3375 -2100);
PAINT WHITE (-3375 -2100);
DISPLAY INVISIBLE (-3375 -2100);
FORCEADD CAP..1
(-2575 -2325);
FORCEPROP 1 LASTPIN (-2575 -2225) $PN 1
J 0
(-2565 -2245);
DISPLAY 0.617021 (-2565 -2245);
PAINT ORANGE (-2565 -2245);
FORCEPROP 1 LASTPIN (-2575 -2425) $PN 2
J 0
(-2565 -2445);
DISPLAY 0.617021 (-2565 -2445);
PAINT ORANGE (-2565 -2445);
FORCEPROP 1 LAST MATERIAL X6S
J 0
(-2525 -2425);
DISPLAY 0.617021 (-2525 -2425);
PAINT SKYBLUE (-2525 -2425);
FORCEPROP 1 LAST VOLTAGE 4V
J 0
(-2525 -2325);
DISPLAY 0.617021 (-2525 -2325);
PAINT SKYBLUE (-2525 -2325);
FORCEPROP 1 LAST PACK_TYPE 0603LF
J 0
(-2525 -2525);
DISPLAY 0.617021 (-2525 -2525);
PAINT SKYBLUE (-2525 -2525);
FORCEPROP 1 LAST TOLERANCE 20%
J 0
(-2525 -2375);
DISPLAY 0.617021 (-2525 -2375);
PAINT SKYBLUE (-2525 -2375);
FORCEPROP 1 LAST VALUE 10UF
J 0
(-2525 -2275);
DISPLAY 0.617021 (-2525 -2275);
PAINT SKYBLUE (-2525 -2275);
FORCEPROP 1 LAST PART_NUMBER E15431-001
J 0
(-2525 -2475);
DISPLAY 0.617021 (-2525 -2475);
PAINT BLUE (-2525 -2475);
FORCEPROP 1 LAST LOCATION C3M18
J 0
(-2525 -2225);
DISPLAY 0.617021 (-2525 -2225);
PAINT AQUA (-2525 -2225);
FORCEPROP 2 LAST CDS_LOCATION C3M18
J 0
(-2525 -2225);
DISPLAY 0.617021 (-2525 -2225);
PAINT AQUA (-2525 -2225);
DISPLAY INVISIBLE (-2525 -2225);
FORCEPROP 2 LAST SEC 1
J 0
(-2525 -2125);
PAINT MONO (-2525 -2125);
DISPLAY INVISIBLE (-2525 -2125);
FORCEPROP 2 LAST SEC_TYPE 0603LF
J 0
(-2525 -2125);
DISPLAY 1.021277 (-2525 -2125);
PAINT ORANGE (-2525 -2125);
DISPLAY INVISIBLE (-2525 -2125);
FORCEPROP 2 LAST BOM_COST SB
J 0
(-2525 -2175);
DISPLAY 1.659574 (-2525 -2175);
PAINT WHITE (-2525 -2175);
DISPLAY INVISIBLE (-2525 -2175);
FORCEPROP 2 LAST CDS_LIB mstr_discrete
J 0
(-2575 -2325);
PAINT ORANGE (-2575 -2325);
DISPLAY INVISIBLE (-2575 -2325);
FORCEPROP 0 LAST CDS_SEC 1
J 0
(-2525 -2175);
PAINT ORANGE (-2525 -2175);
DISPLAY INVISIBLE (-2525 -2175);
FORCEPROP 1 LAST PATH I85
J 0
(-2525 -2175);
DISPLAY 0.978723 (-2525 -2175);
PAINT WHITE (-2525 -2175);
DISPLAY INVISIBLE (-2525 -2175);
FORCEPROP 2 LAST ROOM SB_FILTER_PLL1
J 0
(-2525 -2175);
DISPLAY 1.659574 (-2525 -2175);
PAINT WHITE (-2525 -2175);
DISPLAY INVISIBLE (-2525 -2175);
FORCEADD CAP..1
(-2575 -1075);
FORCEPROP 1 LASTPIN (-2575 -1175) $PN 2
J 0
(-2565 -1195);
DISPLAY 0.617021 (-2565 -1195);
PAINT ORANGE (-2565 -1195);
FORCEPROP 1 LASTPIN (-2575 -975) $PN 1
J 0
(-2565 -995);
DISPLAY 0.617021 (-2565 -995);
PAINT ORANGE (-2565 -995);
FORCEPROP 1 LAST MATERIAL X6S
J 0
(-2525 -1175);
DISPLAY 0.617021 (-2525 -1175);
PAINT SKYBLUE (-2525 -1175);
FORCEPROP 1 LAST VOLTAGE 4V
J 0
(-2525 -1075);
DISPLAY 0.617021 (-2525 -1075);
PAINT SKYBLUE (-2525 -1075);
FORCEPROP 1 LAST PACK_TYPE 0603LF
J 0
(-2525 -1275);
DISPLAY 0.617021 (-2525 -1275);
PAINT SKYBLUE (-2525 -1275);
FORCEPROP 1 LAST TOLERANCE 20%
J 0
(-2525 -1125);
DISPLAY 0.617021 (-2525 -1125);
PAINT SKYBLUE (-2525 -1125);
FORCEPROP 1 LAST VALUE 10UF
J 0
(-2525 -1025);
DISPLAY 0.617021 (-2525 -1025);
PAINT SKYBLUE (-2525 -1025);
FORCEPROP 1 LAST PART_NUMBER E15431-001
J 0
(-2525 -1225);
DISPLAY 0.617021 (-2525 -1225);
PAINT BLUE (-2525 -1225);
FORCEPROP 1 LAST LOCATION C3M17
J 0
(-2525 -975);
DISPLAY 0.617021 (-2525 -975);
PAINT AQUA (-2525 -975);
FORCEPROP 1 LAST PATH I86
J 0
(-2525 -925);
DISPLAY 0.978723 (-2525 -925);
PAINT WHITE (-2525 -925);
DISPLAY INVISIBLE (-2525 -925);
FORCEPROP 0 LAST CDS_SEC 1
J 0
(-2525 -925);
PAINT ORANGE (-2525 -925);
DISPLAY INVISIBLE (-2525 -925);
FORCEPROP 2 LAST BOM_COST SB
J 0
(-2525 -925);
DISPLAY 1.659574 (-2525 -925);
PAINT WHITE (-2525 -925);
DISPLAY INVISIBLE (-2525 -925);
FORCEPROP 2 LAST CDS_LIB mstr_discrete
J 0
(-2575 -1075);
PAINT ORANGE (-2575 -1075);
DISPLAY INVISIBLE (-2575 -1075);
FORCEPROP 2 LAST SEC_TYPE 0603LF
J 0
(-2525 -875);
DISPLAY 1.021277 (-2525 -875);
PAINT ORANGE (-2525 -875);
DISPLAY INVISIBLE (-2525 -875);
FORCEPROP 2 LAST SEC 1
J 0
(-2525 -875);
PAINT MONO (-2525 -875);
DISPLAY INVISIBLE (-2525 -875);
FORCEPROP 2 LAST CDS_LOCATION C3M17
J 0
(-2525 -975);
DISPLAY 0.617021 (-2525 -975);
PAINT AQUA (-2525 -975);
DISPLAY INVISIBLE (-2525 -975);
FORCEPROP 2 LAST ROOM SB_FILTER_PLL0
J 0
(-2525 -925);
DISPLAY 1.659574 (-2525 -925);
PAINT WHITE (-2525 -925);
DISPLAY INVISIBLE (-2525 -925);
FORCEADD CAP_A..1
(-3450 -1050);
FORCEPROP 1 LASTPIN (-3450 -1150) $PN 2
J 0
(-3440 -1170);
DISPLAY 0.617021 (-3440 -1170);
PAINT ORANGE (-3440 -1170);
FORCEPROP 1 LAST MATERIAL X6S
J 0
(-3400 -1150);
DISPLAY 0.617021 (-3400 -1150);
PAINT SKYBLUE (-3400 -1150);
FORCEPROP 1 LAST VOLTAGE 6.3V
J 0
(-3400 -1050);
DISPLAY 0.617021 (-3400 -1050);
PAINT SKYBLUE (-3400 -1050);
FORCEPROP 1 LAST PACK_TYPE 0402V
J 0
(-3400 -1250);
DISPLAY 0.617021 (-3400 -1250);
PAINT SKYBLUE (-3400 -1250);
FORCEPROP 1 LAST TOLERANCE 10%
J 0
(-3400 -1100);
DISPLAY 0.617021 (-3400 -1100);
PAINT SKYBLUE (-3400 -1100);
FORCEPROP 1 LAST PART_NUMBER D97712-004
J 0
(-3400 -1200);
DISPLAY 0.617021 (-3400 -1200);
PAINT BLUE (-3400 -1200);
FORCEPROP 1 LAST LOCATION C3M19
J 0
(-3400 -950);
DISPLAY 0.617021 (-3400 -950);
PAINT AQUA (-3400 -950);
FORCEPROP 1 LASTPIN (-3450 -950) $PN 1
J 0
(-3440 -970);
DISPLAY 0.617021 (-3440 -970);
PAINT ORANGE (-3440 -970);
FORCEPROP 1 LAST VALUE 1.0UF
J 0
(-3400 -1000);
DISPLAY 0.617021 (-3400 -1000);
PAINT SKYBLUE (-3400 -1000);
FORCEPROP 2 LAST CDS_LOCATION C3M19
J 0
(-3400 -950);
DISPLAY 0.617021 (-3400 -950);
PAINT AQUA (-3400 -950);
DISPLAY INVISIBLE (-3400 -950);
FORCEPROP 2 LAST BOM_COST SB
J 0
(-3400 -900);
DISPLAY 1.659574 (-3400 -900);
PAINT WHITE (-3400 -900);
DISPLAY INVISIBLE (-3400 -900);
FORCEPROP 2 LAST CDS_LIB dev_discrete
J 0
(-3450 -1050);
PAINT ORANGE (-3450 -1050);
DISPLAY INVISIBLE (-3450 -1050);
FORCEPROP 2 LAST CDS_SEC 1
J 0
(-3400 -900);
PAINT ORANGE (-3400 -900);
DISPLAY INVISIBLE (-3400 -900);
FORCEPROP 2 LAST SEC_TYPE 0402V
J 0
(-3400 -850);
DISPLAY 1.021277 (-3400 -850);
PAINT ORANGE (-3400 -850);
DISPLAY INVISIBLE (-3400 -850);
FORCEPROP 2 LAST SEC 1
J 0
(-3400 -850);
DISPLAY 0.680851 (-3400 -850);
PAINT MONO (-3400 -850);
DISPLAY INVISIBLE (-3400 -850);
FORCEPROP 1 LAST PATH I87
J 0
(-3400 -900);
DISPLAY 0.978723 (-3400 -900);
PAINT WHITE (-3400 -900);
DISPLAY INVISIBLE (-3400 -900);
FORCEPROP 2 LAST ROOM SB_FILTER_PLL0
J 0
(-3400 -900);
DISPLAY 1.659574 (-3400 -900);
PAINT WHITE (-3400 -900);
DISPLAY INVISIBLE (-3400 -900);
FORCEADD CAP_A..1
R 2
(-4300 -1050);
FORCEPROP 1 LASTPIN (-4300 -1150) $PN 2
J 2
(-4310 -1170);
DISPLAY 0.617021 (-4310 -1170);
PAINT ORANGE (-4310 -1170);
FORCEPROP 1 LASTPIN (-4300 -950) $PN 1
J 2
(-4310 -970);
DISPLAY 0.617021 (-4310 -970);
PAINT ORANGE (-4310 -970);
FORCEPROP 1 LAST MATERIAL X6S
J 2
(-4350 -1150);
DISPLAY 0.617021 (-4350 -1150);
PAINT SKYBLUE (-4350 -1150);
FORCEPROP 1 LAST VOLTAGE 6.3V
J 2
(-4350 -1050);
DISPLAY 0.617021 (-4350 -1050);
PAINT SKYBLUE (-4350 -1050);
FORCEPROP 1 LAST PACK_TYPE 0402V
J 2
(-4350 -1250);
DISPLAY 0.617021 (-4350 -1250);
PAINT SKYBLUE (-4350 -1250);
FORCEPROP 1 LAST TOLERANCE 10%
J 2
(-4350 -1100);
DISPLAY 0.617021 (-4350 -1100);
PAINT SKYBLUE (-4350 -1100);
FORCEPROP 1 LAST VALUE 1.0UF
J 2
(-4350 -1000);
DISPLAY 0.617021 (-4350 -1000);
PAINT SKYBLUE (-4350 -1000);
FORCEPROP 1 LAST PART_NUMBER D97712-004
J 2
(-4350 -1200);
DISPLAY 0.617021 (-4350 -1200);
PAINT BLUE (-4350 -1200);
FORCEPROP 1 LAST LOCATION C3M21
J 2
(-4350 -950);
DISPLAY 0.617021 (-4350 -950);
PAINT AQUA (-4350 -950);
FORCEPROP 1 LAST PATH I9
J 2
(-4350 -900);
DISPLAY 0.978723 (-4350 -900);
PAINT WHITE (-4350 -900);
DISPLAY INVISIBLE (-4350 -900);
FORCEPROP 2 LAST SEC 1
J 0
(-4350 -850);
PAINT MONO (-4350 -850);
DISPLAY INVISIBLE (-4350 -850);
FORCEPROP 2 LAST SEC_TYPE 0402V
J 0
(-4350 -850);
DISPLAY 1.021277 (-4350 -850);
PAINT ORANGE (-4350 -850);
DISPLAY INVISIBLE (-4350 -850);
FORCEPROP 2 LAST CDS_SEC 1
J 0
(-4350 -900);
PAINT ORANGE (-4350 -900);
DISPLAY INVISIBLE (-4350 -900);
FORCEPROP 2 LAST CDS_LIB dev_discrete
J 0
(-4300 -1050);
PAINT ORANGE (-4300 -1050);
DISPLAY INVISIBLE (-4300 -1050);
FORCEPROP 2 LAST BOM_COST SB
J 2
(-4350 -900);
DISPLAY 1.659574 (-4350 -900);
PAINT WHITE (-4350 -900);
DISPLAY INVISIBLE (-4350 -900);
FORCEPROP 2 LAST CDS_LOCATION C3M21
J 2
(-4350 -950);
DISPLAY 0.617021 (-4350 -950);
PAINT AQUA (-4350 -950);
DISPLAY INVISIBLE (-4350 -950);
FORCEPROP 2 LAST ROOM SB_FILTER_PLL0
J 2
(-4350 -900);
DISPLAY 1.659574 (-4350 -900);
PAINT WHITE (-4350 -900);
DISPLAY INVISIBLE (-4350 -900);
FORCEADD INTEL_CORP_BPAGE..1
(2775 -5050);
FORCEPROP 1 LAST CDS_CON_LAST_MODIFIED Fri Jun 16 17:48:49 2017
J 0
(1350 -4725);
DISPLAY 1.361702 (1350 -4725);
PAINT ORANGE (1350 -4725);
DISPLAY INVISIBLE (1350 -4725);
FORCEPROP 1 LAST CUSTOM_TXT_CDS <CURRENT_DESIGN_SHEET> OF <TOTAL_DESIGN_SHEETS>
J 0
(2275 -5025);
PAINT ORANGE (2275 -5025);
FORCEPROP 2 LAST CUSTOM_TXT_CDS <XR_PAGE_TITLE>
J 0
(-5115 200);
DISPLAY 0.638298 (-5115 200);
PAINT PINK (-5115 200);
DISPLAY INVISIBLE (-5115 200);
FORCEPROP 2 LAST CUSTOM_TXT_CDS <CON_LAST_MODIFIED>
J 0
(-1225 -4950);
DISPLAY 1.361702 (-1225 -4950);
PAINT ORANGE (-1225 -4950);
FORCEPROP 1 LAST SCH_TITLE LBG PLL FILTERS
J 0
(-5175 -5000);
DISPLAY 1.212766 (-5175 -5000);
PAINT ORANGE (-5175 -5000);
FORCEPROP 1 LAST COMMENT_BODY TRUE
J 0
(2787 -5038);
DISPLAY 0.617021 (2787 -5038);
PAINT GREEN (2787 -5038);
DISPLAY INVISIBLE (2787 -5038);
FORCEPROP 2 LAST CDS_LIB mstr_symbols
J 0
(2775 -5050);
DISPLAY 1.361702 (2775 -5050);
PAINT MONO (2775 -5050);
DISPLAY INVISIBLE (2775 -5050);
FORCEPROP 2 LAST PAGE_BORDER TRUE
J 0
(-5115 200);
DISPLAY 0.851064 (-5115 200);
PAINT PINK (-5115 200);
DISPLAY INVISIBLE (-5115 200);
FORCEPROP 2 LAST CDS_XR_PAGE_TITLE CR-127 : @BASEBOARD_FAB2_LIB.BASEBOARD_FAB2(SCH_1):PAGE127
J 0
(-5115 200);
DISPLAY 0.638298 (-5115 200);
PAINT PINK (-5115 200);
DISPLAY INVISIBLE (-5115 200);
WIRE 16 -1 (-3425 -2550)(-3425 -2500);
WIRE 16 -1 (-3425 -2500)(-4275 -2500);
WIRE 16 -1 (-3425 -2350)(-3425 -2500);
WIRE 16 -1 (-4275 -2350)(-4275 -2500);
WIRE 16 -1 (-4275 -1750)(-4275 -2050);
WIRE 16 -1 (-4275 -2150)(-4275 -2050);
WIRE 16 -1 (-4275 -2050)(-4125 -2050);
WIRE 16 -1 (-3400 -3850)(-3400 -3800);
WIRE 16 -1 (-3400 -3800)(-4250 -3800);
WIRE 16 -1 (-3400 -3650)(-3400 -3800);
WIRE 16 -1 (-4250 -3650)(-4250 -3800);
WIRE 16 -1 (-4250 -3050)(-4250 -3350);
WIRE 16 -1 (-4250 -3450)(-4250 -3350);
WIRE 16 -1 (-4250 -3350)(-4100 -3350);
WIRE 16 -1 (-2575 -1175)(-2575 -1275);
WIRE 16 -1 (-2575 -2425)(-2575 -2550);
WIRE 16 -1 (-2550 -3700)(-2550 -3800);
WIRE 16 -1 (-2550 -3025)(-2550 -3350);
WIRE 16 -1 (-3400 -3350)(-2550 -3350);
FORCEPROP 0 LAST VOLTAGE +1.05V
J 0
(-2950 -3300);
DISPLAY 1.021277 (-2950 -3300);
PAINT SKYBLUE (-2950 -3300);
DISPLAY INVISIBLE (-2950 -3300);
WIRE 16 -1 (-2550 -3500)(-2550 -3350);
WIRE 16 -1 (-3900 -3350)(-3400 -3350);
WIRE 16 -1 (-3400 -3450)(-3400 -3350);
WIRE 16 -1 (1850 -800)(1850 -1175);
WIRE 16 -1 (1400 -1175)(1850 -1175);
WIRE 16 -1 (1850 -1275)(1850 -1175);
WIRE 16 -1 (1250 -1175)(1400 -1175);
FORCEPROP 2 LAST VOLTAGE 1.05V
J 0
(1375 -1100);
PAINT SKYBLUE (1375 -1100);
DISPLAY INVISIBLE (1375 -1100);
WIRE 16 -1 (1400 -1275)(1400 -1175);
WIRE 16 -1 (950 -875)(950 -1175);
WIRE 16 -1 (950 -1175)(1050 -1175);
WIRE 16 -1 (950 -1175)(950 -1275);
WIRE 16 -1 (-500 -850)(-500 -1200);
WIRE 16 -1 (-1000 -1200)(-500 -1200);
WIRE 16 -1 (-500 -1200)(-500 -1300);
WIRE 16 -1 (-1125 -1200)(-1000 -1200);
FORCEPROP 2 LAST VOLTAGE 1.05V
J 0
(-1000 -1125);
PAINT SKYBLUE (-1000 -1125);
DISPLAY INVISIBLE (-1000 -1125);
WIRE 16 -1 (-1000 -1300)(-1000 -1200);
WIRE 16 -1 (-1125 -1200)(-1125 -1225);
WIRE 16 -1 (1400 -1625)(1400 -1675);
WIRE 16 -1 (1400 -1625)(1850 -1625);
WIRE 16 -1 (1400 -1475)(1400 -1625);
WIRE 16 -1 (1850 -1475)(1850 -1625);
WIRE 16 -1 (1700 -3075)(1700 -2750);
WIRE 16 -1 (1400 -3075)(1700 -3075);
WIRE 16 -1 (1700 -3075)(1700 -3175);
WIRE 16 -1 (1250 -3075)(1400 -3075);
FORCEPROP 2 LAST VOLTAGE 1.05V
J 0
(1375 -3000);
PAINT SKYBLUE (1375 -3000);
DISPLAY INVISIBLE (1375 -3000);
WIRE 16 -1 (1400 -3175)(1400 -3075);
WIRE 16 -1 (950 -2775)(950 -3075);
WIRE 16 -1 (950 -3175)(950 -3075);
WIRE 16 -1 (950 -3075)(1050 -3075);
WIRE 16 -1 (1700 -3375)(1700 -3575);
WIRE 16 -1 (950 -3525)(950 -3625);
WIRE 16 -1 (950 -3525)(1400 -3525);
WIRE 16 -1 (950 -3375)(950 -3525);
WIRE 16 -1 (1400 -3375)(1400 -3525);
WIRE 16 -1 (-3450 -1350)(-3450 -1300);
WIRE 16 -1 (-3450 -1300)(-4300 -1300);
WIRE 16 -1 (-3450 -1150)(-3450 -1300);
WIRE 16 -1 (-4300 -1150)(-4300 -1300);
WIRE 16 -1 (-1000 -1650)(-1000 -1700);
WIRE 16 -1 (-1000 -1650)(-500 -1650);
WIRE 16 -1 (-1000 -1500)(-1000 -1650);
WIRE 16 -1 (-500 -1500)(-500 -1650);
WIRE 16 -1 (-500 -3100)(-500 -2700);
WIRE 16 -1 (-1000 -3100)(-500 -3100);
WIRE 16 -1 (-500 -3200)(-500 -3100);
WIRE 16 -1 (-1150 -3100)(-1000 -3100);
FORCEPROP 2 LAST VOLTAGE 1.05V
J 0
(-1000 -3025);
PAINT SKYBLUE (-1000 -3025);
DISPLAY INVISIBLE (-1000 -3025);
WIRE 16 -1 (-1000 -3200)(-1000 -3100);
WIRE 16 -1 (-500 -3550)(-500 -3600);
WIRE 16 -1 (-500 -3550)(-1000 -3550);
WIRE 16 -1 (-500 -3400)(-500 -3550);
WIRE 16 -1 (-1000 -3400)(-1000 -3550);
WIRE 16 -1 (-1450 -900)(-1450 -1200);
WIRE 16 -1 (-1450 -1200)(-1325 -1200);
WIRE 16 -1 (-1450 -1200)(-1450 -1300);
WIRE 16 -1 (-4300 -550)(-4300 -850);
WIRE 16 -1 (-4300 -950)(-4300 -850);
WIRE 16 -1 (-4300 -850)(-4150 -850);
WIRE 16 -1 (-1450 -2775)(-1450 -3100);
WIRE 16 -1 (-1450 -3200)(-1450 -3100);
WIRE 16 -1 (-1450 -3100)(-1350 -3100);
WIRE 16 -1 (-2575 -1725)(-2575 -2050);
WIRE 16 -1 (-3425 -2050)(-2575 -2050);
FORCEPROP 0 LAST VOLTAGE +1.05V
J 0
(-2975 -2000);
DISPLAY 1.021277 (-2975 -2000);
PAINT SKYBLUE (-2975 -2000);
DISPLAY INVISIBLE (-2975 -2000);
WIRE 16 -1 (-2575 -2225)(-2575 -2050);
WIRE 16 -1 (-3925 -2050)(-3425 -2050);
WIRE 16 -1 (-3425 -2150)(-3425 -2050);
WIRE 16 -1 (-2575 -525)(-2575 -850);
WIRE 16 -1 (-3450 -850)(-2575 -850);
FORCEPROP 0 LAST VOLTAGE +1.05V
J 0
(-3000 -800);
DISPLAY 1.021277 (-3000 -800);
PAINT SKYBLUE (-3000 -800);
DISPLAY INVISIBLE (-3000 -800);
WIRE 16 -1 (-2575 -975)(-2575 -850);
WIRE 16 -1 (-3950 -850)(-3450 -850);
WIRE 16 -1 (-3450 -950)(-3450 -850);
WIRE 16 -1 (-1450 -1500)(-1450 -1700);
WIRE 16 -1 (950 -1475)(950 -1675);
WIRE 16 -1 (-1450 -3400)(-1450 -3575);
DOT 1 (-4300 -850);
DOT 1 (1700 -3075);
DOT 1 (1400 -3075);
DOT 1 (-1000 -3100);
DOT 1 (-2550 -3350);
DOT 1 (-2575 -850);
DOT 1 (-3450 -850);
DOT 1 (-3450 -1300);
DOT 1 (-2575 -2050);
DOT 1 (-3425 -2050);
DOT 1 (-3425 -2500);
DOT 1 (-3400 -3350);
DOT 1 (-3400 -3800);
DOT 1 (-4275 -2050);
DOT 1 (-4250 -3350);
DOT 1 (1850 -1175);
DOT 1 (1400 -1175);
DOT 1 (1400 -1625);
DOT 1 (950 -3075);
DOT 1 (950 -3525);
DOT 1 (-500 -1200);
DOT 1 (-1000 -1200);
DOT 1 (-1000 -1650);
DOT 1 (-500 -3100);
DOT 1 (-500 -3550);
DOT 1 (-1450 -1200);
DOT 1 (950 -1175);
DOT 1 (-1450 -3100);
FORCENOTE
ROOM=SB_FILTER_WM26
(-1400 -1972) 0;
DISPLAY LEFT (-1400 -1972);
PAINT PURPLE (-1400 -1972);
FORCENOTE
ROOM=SB_FILTER_WM20
(975 -1872) 0;
DISPLAY LEFT (975 -1872);
PAINT PURPLE (975 -1872);
FORCENOTE
ROOM=SB
(-4975 -4750) 0;
DISPLAY LEFT (-4975 -4750);
DISPLAY 1.021277 (-4975 -4750);
PAINT PURPLE (-4975 -4750);
FORCENOTE
ROOM=SB_FILTER_XTAL
(-3275 -3975) 0;
DISPLAY LEFT (-3275 -3975);
DISPLAY 0.808511 (-3275 -3975);
PAINT PURPLE (-3275 -3975);
FORCENOTE
ROOM=SB_FILTER_PLL1
(-3350 -2625) 0;
DISPLAY LEFT (-3350 -2625);
DISPLAY 0.808511 (-3350 -2625);
PAINT PURPLE (-3350 -2625);
FORCENOTE
ROOM=SB_FILTER_PLL0
(-3300 -1425) 0;
DISPLAY LEFT (-3300 -1425);
DISPLAY 0.808511 (-3300 -1425);
PAINT PURPLE (-3300 -1425);
FORCENOTE
ROOM=SB_FILTER_KR_PLL
(-1425 -3822) 0;
DISPLAY LEFT (-1425 -3822);
PAINT PURPLE (-1425 -3822);
FORCENOTE
ROOM=SB_FILTER_ISCLK
(975 -3797) 0;
DISPLAY LEFT (975 -3797);
PAINT PURPLE (975 -3797);
QUIT
